FILE_TYPE = MACRO_DRAWING;
SET COLOR_WIRE YELLOW;
SET COLOR_PROP ORANGE;
SET COLOR_DOT WHITE;
SET COLOR_ARC YELLOW;
SET COLOR_BODY GREEN;
SET COLOR_NOTE PURPLE;
SET PROP_DISPLAY VALUE;
SET PAGE_NUMBER P20;
FORCEADD SOCKET4677_AZIF0045P001C01CS..8
(1100 2100);
FORCEPROP 1 LAST PART_NUMBER DGA^7000023
J 0
(0 4450);
DISPLAY 0.723404 (0 4450);
PAINT GREEN (0 4450);
DISPLAY INVISIBLE (0 4450);
FORCEPROP 2 LAST PART_TYPE SMLF
J 0
(0 4625);
DISPLAY 1.021277 (0 4625);
FORCEPROP 1 LAST MATERIAL IO
J 0
(0 4375);
DISPLAY 0.723404 (0 4375);
PAINT GREEN (0 4375);
FORCEPROP 2 LAST VALUE SOCKET4677_AZIF0045-P001C01CS
J 0
(0 4575);
DISPLAY 1.021277 (0 4575);
FORCEPROP 1 LAST $LOCATION U2
J 0
(0 4525);
DISPLAY 0.723404 (0 4525);
PAINT GREEN (0 4525);
FORCEPROP 0 LASTPIN (2325 250) $PN AT42
J 0
(2335 260);
DISPLAY 0.680851 (2335 260);
PAINT MONO (2335 260);
FORCEPROP 0 LASTPIN (2325 300) $PN AU43
J 0
(2335 310);
DISPLAY 0.680851 (2335 310);
PAINT MONO (2335 310);
FORCEPROP 0 LASTPIN (2325 0) $PN AT49
J 0
(2335 10);
DISPLAY 0.680851 (2335 10);
PAINT MONO (2335 10);
FORCEPROP 0 LASTPIN (2325 100) $PN AV44
J 0
(2335 110);
DISPLAY 0.680851 (2335 110);
PAINT MONO (2335 110);
FORCEPROP 0 LASTPIN (2325 150) $PN AV42
J 0
(2335 160);
DISPLAY 0.680851 (2335 160);
PAINT MONO (2335 160);
FORCEPROP 0 LASTPIN (-125 0) $PN B44
J 2
(-135 10);
DISPLAY 0.680851 (-135 10);
PAINT MONO (-135 10);
FORCEPROP 0 LASTPIN (-125 50) $PN G45
J 2
(-135 60);
DISPLAY 0.680851 (-135 60);
PAINT MONO (-135 60);
FORCEPROP 0 LASTPIN (-125 100) $PN C43
J 2
(-135 110);
DISPLAY 0.680851 (-135 110);
PAINT MONO (-135 110);
FORCEPROP 0 LASTPIN (-125 150) $PN E45
J 2
(-135 160);
DISPLAY 0.680851 (-135 160);
PAINT MONO (-135 160);
FORCEPROP 0 LASTPIN (2325 1600) $PN A52
J 0
(2335 1610);
DISPLAY 0.680851 (2335 1610);
PAINT MONO (2335 1610);
FORCEPROP 0 LASTPIN (2325 1650) $PN G52
J 0
(2335 1660);
DISPLAY 0.680851 (2335 1660);
PAINT MONO (2335 1660);
FORCEPROP 0 LASTPIN (2325 1700) $PN B51
J 0
(2335 1710);
DISPLAY 0.680851 (2335 1710);
PAINT MONO (2335 1710);
FORCEPROP 0 LASTPIN (2325 1750) $PN F51
J 0
(2335 1760);
DISPLAY 0.680851 (2335 1760);
PAINT MONO (2335 1760);
FORCEPROP 0 LASTPIN (2325 1800) $PN C50
J 0
(2335 1810);
DISPLAY 0.680851 (2335 1810);
PAINT MONO (2335 1810);
FORCEPROP 0 LASTPIN (2325 1850) $PN E50
J 0
(2335 1860);
DISPLAY 0.680851 (2335 1860);
PAINT MONO (2335 1860);
FORCEPROP 0 LASTPIN (2325 1900) $PN C48
J 0
(2335 1910);
DISPLAY 0.680851 (2335 1910);
PAINT MONO (2335 1910);
FORCEPROP 0 LASTPIN (-125 2650) $PN B81
J 2
(-135 2660);
DISPLAY 0.680851 (-135 2660);
PAINT MONO (-135 2660);
FORCEPROP 0 LASTPIN (-125 2700) $PN B79
J 2
(-135 2710);
DISPLAY 0.680851 (-135 2710);
PAINT MONO (-135 2710);
FORCEPROP 0 LASTPIN (-125 2750) $PN M77
J 2
(-135 2760);
DISPLAY 0.680851 (-135 2760);
PAINT MONO (-135 2760);
FORCEPROP 0 LASTPIN (-125 2800) $PN G78
J 2
(-135 2810);
DISPLAY 0.680851 (-135 2810);
PAINT MONO (-135 2810);
FORCEPROP 0 LASTPIN (-125 2850) $PN C76
J 2
(-135 2860);
DISPLAY 0.680851 (-135 2860);
PAINT MONO (-135 2860);
FORCEPROP 0 LASTPIN (-125 2900) $PN D75
J 2
(-135 2910);
DISPLAY 0.680851 (-135 2910);
PAINT MONO (-135 2910);
FORCEPROP 0 LASTPIN (-125 2950) $PN G76
J 2
(-135 2960);
DISPLAY 0.680851 (-135 2960);
PAINT MONO (-135 2960);
FORCEPROP 0 LASTPIN (-125 3000) $PN F75
J 2
(-135 3010);
DISPLAY 0.680851 (-135 3010);
PAINT MONO (-135 3010);
FORCEPROP 0 LASTPIN (-125 3050) $PN K69
J 2
(-135 3060);
DISPLAY 0.680851 (-135 3060);
PAINT MONO (-135 3060);
FORCEPROP 0 LASTPIN (-125 3100) $PN J68
J 2
(-135 3110);
DISPLAY 0.680851 (-135 3110);
PAINT MONO (-135 3110);
FORCEPROP 0 LASTPIN (-125 3150) $PN M69
J 2
(-135 3160);
DISPLAY 0.680851 (-135 3160);
PAINT MONO (-135 3160);
FORCEPROP 0 LASTPIN (-125 3200) $PN N68
J 2
(-135 3210);
DISPLAY 0.680851 (-135 3210);
PAINT MONO (-135 3210);
FORCEPROP 0 LASTPIN (-125 3250) $PN J66
J 2
(-135 3260);
DISPLAY 0.680851 (-135 3260);
PAINT MONO (-135 3260);
FORCEPROP 0 LASTPIN (-125 3300) $PN K65
J 2
(-135 3310);
DISPLAY 0.680851 (-135 3310);
PAINT MONO (-135 3310);
FORCEPROP 0 LASTPIN (-125 3350) $PN N66
J 2
(-135 3360);
DISPLAY 0.680851 (-135 3360);
PAINT MONO (-135 3360);
FORCEPROP 0 LASTPIN (-125 3400) $PN M65
J 2
(-135 3410);
DISPLAY 0.680851 (-135 3410);
PAINT MONO (-135 3410);
FORCEPROP 0 LASTPIN (-125 3450) $PN B73
J 2
(-135 3460);
DISPLAY 0.680851 (-135 3460);
PAINT MONO (-135 3460);
FORCEPROP 0 LASTPIN (-125 3500) $PN E72
J 2
(-135 3510);
DISPLAY 0.680851 (-135 3510);
PAINT MONO (-135 3510);
FORCEPROP 0 LASTPIN (-125 3550) $PN D73
J 2
(-135 3560);
DISPLAY 0.680851 (-135 3560);
PAINT MONO (-135 3560);
FORCEPROP 0 LASTPIN (-125 3600) $PN F71
J 2
(-135 3610);
DISPLAY 0.680851 (-135 3610);
PAINT MONO (-135 3610);
FORCEPROP 0 LASTPIN (-125 3650) $PN B69
J 2
(-135 3660);
DISPLAY 0.680851 (-135 3660);
PAINT MONO (-135 3660);
FORCEPROP 0 LASTPIN (-125 3700) $PN C68
J 2
(-135 3710);
DISPLAY 0.680851 (-135 3710);
PAINT MONO (-135 3710);
FORCEPROP 0 LASTPIN (-125 3750) $PN F69
J 2
(-135 3760);
DISPLAY 0.680851 (-135 3760);
PAINT MONO (-135 3760);
FORCEPROP 0 LASTPIN (-125 3800) $PN E68
J 2
(-135 3810);
DISPLAY 0.680851 (-135 3810);
PAINT MONO (-135 3810);
FORCEPROP 0 LASTPIN (-125 3850) $PN C66
J 2
(-135 3860);
DISPLAY 0.680851 (-135 3860);
PAINT MONO (-135 3860);
FORCEPROP 0 LASTPIN (-125 3900) $PN B65
J 2
(-135 3910);
DISPLAY 0.680851 (-135 3910);
PAINT MONO (-135 3910);
FORCEPROP 0 LASTPIN (-125 3950) $PN E66
J 2
(-135 3960);
DISPLAY 0.680851 (-135 3960);
PAINT MONO (-135 3960);
FORCEPROP 0 LASTPIN (-125 4000) $PN F65
J 2
(-135 4010);
DISPLAY 0.680851 (-135 4010);
PAINT MONO (-135 4010);
FORCEPROP 0 LASTPIN (-125 4050) $PN B63
J 2
(-135 4060);
DISPLAY 0.680851 (-135 4060);
PAINT MONO (-135 4060);
FORCEPROP 0 LASTPIN (-125 4100) $PN C62
J 2
(-135 4110);
DISPLAY 0.680851 (-135 4110);
PAINT MONO (-135 4110);
FORCEPROP 0 LASTPIN (-125 4150) $PN F63
J 2
(-135 4160);
DISPLAY 0.680851 (-135 4160);
PAINT MONO (-135 4160);
FORCEPROP 0 LASTPIN (-125 4200) $PN E62
J 2
(-135 4210);
DISPLAY 0.680851 (-135 4210);
PAINT MONO (-135 4210);
FORCEPROP 0 LASTPIN (2325 3200) $PN B77
J 0
(2335 3210);
DISPLAY 0.680851 (2335 3210);
PAINT MONO (2335 3210);
FORCEPROP 0 LASTPIN (2325 3250) $PN H67
J 0
(2335 3260);
DISPLAY 0.680851 (2335 3260);
PAINT MONO (2335 3260);
FORCEPROP 0 LASTPIN (2325 3300) $PN B71
J 0
(2335 3310);
DISPLAY 0.680851 (2335 3310);
PAINT MONO (2335 3310);
FORCEPROP 0 LASTPIN (2325 3350) $PN A64
J 0
(2335 3360);
DISPLAY 0.680851 (2335 3360);
PAINT MONO (2335 3360);
FORCEPROP 0 LASTPIN (2325 3400) $PN A58
J 0
(2335 3410);
DISPLAY 0.680851 (2335 3410);
PAINT MONO (2335 3410);
FORCEPROP 0 LASTPIN (2325 3450) $PN H77
J 0
(2335 3460);
DISPLAY 0.680851 (2335 3460);
PAINT MONO (2335 3460);
FORCEPROP 0 LASTPIN (2325 3500) $PN P67
J 0
(2335 3510);
DISPLAY 0.680851 (2335 3510);
PAINT MONO (2335 3510);
FORCEPROP 0 LASTPIN (2325 3550) $PN G70
J 0
(2335 3560);
DISPLAY 0.680851 (2335 3560);
PAINT MONO (2335 3560);
FORCEPROP 0 LASTPIN (2325 3600) $PN G64
J 0
(2335 3610);
DISPLAY 0.680851 (2335 3610);
PAINT MONO (2335 3610);
FORCEPROP 0 LASTPIN (2325 3650) $PN G58
J 0
(2335 3660);
DISPLAY 0.680851 (2335 3660);
PAINT MONO (2335 3660);
FORCEPROP 0 LASTPIN (2325 3750) $PN D77
J 0
(2335 3760);
DISPLAY 0.680851 (2335 3760);
PAINT MONO (2335 3760);
FORCEPROP 0 LASTPIN (2325 3800) $PN K67
J 0
(2335 3810);
DISPLAY 0.680851 (2335 3810);
PAINT MONO (2335 3810);
FORCEPROP 0 LASTPIN (2325 3850) $PN C70
J 0
(2335 3860);
DISPLAY 0.680851 (2335 3860);
PAINT MONO (2335 3860);
FORCEPROP 0 LASTPIN (2325 3900) $PN C64
J 0
(2335 3910);
DISPLAY 0.680851 (2335 3910);
PAINT MONO (2335 3910);
FORCEPROP 0 LASTPIN (2325 3950) $PN C58
J 0
(2335 3960);
DISPLAY 0.680851 (2335 3960);
PAINT MONO (2335 3960);
FORCEPROP 0 LASTPIN (2325 4000) $PN F77
J 0
(2335 4010);
DISPLAY 0.680851 (2335 4010);
PAINT MONO (2335 4010);
FORCEPROP 0 LASTPIN (2325 4050) $PN M67
J 0
(2335 4060);
DISPLAY 0.680851 (2335 4060);
PAINT MONO (2335 4060);
FORCEPROP 0 LASTPIN (2325 4100) $PN E70
J 0
(2335 4110);
DISPLAY 0.680851 (2335 4110);
PAINT MONO (2335 4110);
FORCEPROP 0 LASTPIN (2325 4150) $PN E64
J 0
(2335 4160);
DISPLAY 0.680851 (2335 4160);
PAINT MONO (2335 4160);
FORCEPROP 0 LASTPIN (2325 4200) $PN E58
J 0
(2335 4210);
DISPLAY 0.680851 (2335 4210);
PAINT MONO (2335 4210);
FORCEPROP 0 LASTPIN (-125 2250) $PN C60
J 2
(-135 2260);
DISPLAY 0.680851 (-135 2260);
PAINT MONO (-135 2260);
FORCEPROP 0 LASTPIN (-125 2300) $PN B59
J 2
(-135 2310);
DISPLAY 0.680851 (-135 2310);
PAINT MONO (-135 2310);
FORCEPROP 0 LASTPIN (-125 2350) $PN E60
J 2
(-135 2360);
DISPLAY 0.680851 (-135 2360);
PAINT MONO (-135 2360);
FORCEPROP 0 LASTPIN (-125 2400) $PN F59
J 2
(-135 2410);
DISPLAY 0.680851 (-135 2410);
PAINT MONO (-135 2410);
FORCEPROP 0 LASTPIN (-125 2450) $PN B57
J 2
(-135 2460);
DISPLAY 0.680851 (-135 2460);
PAINT MONO (-135 2460);
FORCEPROP 0 LASTPIN (-125 2500) $PN C56
J 2
(-135 2510);
DISPLAY 0.680851 (-135 2510);
PAINT MONO (-135 2510);
FORCEPROP 0 LASTPIN (-125 2550) $PN F57
J 2
(-135 2560);
DISPLAY 0.680851 (-135 2560);
PAINT MONO (-135 2560);
FORCEPROP 0 LASTPIN (-125 2600) $PN E56
J 2
(-135 2610);
DISPLAY 0.680851 (-135 2610);
PAINT MONO (-135 2610);
FORCEPROP 0 LASTPIN (2325 1550) $PN E48
J 0
(2335 1560);
DISPLAY 0.680851 (2335 1560);
PAINT MONO (2335 1560);
FORCEPROP 0 LASTPIN (2325 1100) $PN E43
J 0
(2335 1110);
DISPLAY 0.680851 (2335 1110);
PAINT MONO (2335 1110);
FORCEPROP 0 LASTPIN (2325 1150) $PN F44
J 0
(2335 1160);
DISPLAY 0.680851 (2335 1160);
PAINT MONO (2335 1160);
FORCEPROP 0 LASTPIN (2325 1200) $PN C41
J 0
(2335 1210);
DISPLAY 0.680851 (2335 1210);
PAINT MONO (2335 1210);
FORCEPROP 0 LASTPIN (2325 1250) $PN E41
J 0
(2335 1260);
DISPLAY 0.680851 (2335 1260);
PAINT MONO (2335 1260);
FORCEPROP 0 LASTPIN (2325 1300) $PN B40
J 0
(2335 1310);
DISPLAY 0.680851 (2335 1310);
PAINT MONO (2335 1310);
FORCEPROP 0 LASTPIN (2325 1350) $PN F40
J 0
(2335 1360);
DISPLAY 0.680851 (2335 1360);
PAINT MONO (2335 1360);
FORCEPROP 0 LASTPIN (2325 1400) $PN A39
J 0
(2335 1410);
DISPLAY 0.680851 (2335 1410);
PAINT MONO (2335 1410);
FORCEPROP 0 LASTPIN (-125 650) $PN K32
J 2
(-135 660);
DISPLAY 0.680851 (-135 660);
PAINT MONO (-135 660);
FORCEPROP 0 LASTPIN (-125 700) $PN J31
J 2
(-135 710);
DISPLAY 0.680851 (-135 710);
PAINT MONO (-135 710);
FORCEPROP 0 LASTPIN (-125 750) $PN M32
J 2
(-135 760);
DISPLAY 0.680851 (-135 760);
PAINT MONO (-135 760);
FORCEPROP 0 LASTPIN (-125 800) $PN N31
J 2
(-135 810);
DISPLAY 0.680851 (-135 810);
PAINT MONO (-135 810);
FORCEPROP 0 LASTPIN (-125 850) $PN J29
J 2
(-135 860);
DISPLAY 0.680851 (-135 860);
PAINT MONO (-135 860);
FORCEPROP 0 LASTPIN (-125 900) $PN K28
J 2
(-135 910);
DISPLAY 0.680851 (-135 910);
PAINT MONO (-135 910);
FORCEPROP 0 LASTPIN (-125 950) $PN N29
J 2
(-135 960);
DISPLAY 0.680851 (-135 960);
PAINT MONO (-135 960);
FORCEPROP 0 LASTPIN (-125 1000) $PN M28
J 2
(-135 1010);
DISPLAY 0.680851 (-135 1010);
PAINT MONO (-135 1010);
FORCEPROP 0 LASTPIN (-125 1050) $PN C29
J 2
(-135 1060);
DISPLAY 0.680851 (-135 1060);
PAINT MONO (-135 1060);
FORCEPROP 0 LASTPIN (-125 1100) $PN B28
J 2
(-135 1110);
DISPLAY 0.680851 (-135 1110);
PAINT MONO (-135 1110);
FORCEPROP 0 LASTPIN (-125 1150) $PN E29
J 2
(-135 1160);
DISPLAY 0.680851 (-135 1160);
PAINT MONO (-135 1160);
FORCEPROP 0 LASTPIN (-125 1200) $PN F28
J 2
(-135 1210);
DISPLAY 0.680851 (-135 1210);
PAINT MONO (-135 1210);
FORCEPROP 0 LASTPIN (-125 1250) $PN B26
J 2
(-135 1260);
DISPLAY 0.680851 (-135 1260);
PAINT MONO (-135 1260);
FORCEPROP 0 LASTPIN (-125 1300) $PN C25
J 2
(-135 1310);
DISPLAY 0.680851 (-135 1310);
PAINT MONO (-135 1310);
FORCEPROP 0 LASTPIN (-125 1350) $PN F26
J 2
(-135 1360);
DISPLAY 0.680851 (-135 1360);
PAINT MONO (-135 1360);
FORCEPROP 0 LASTPIN (-125 1400) $PN E25
J 2
(-135 1410);
DISPLAY 0.680851 (-135 1410);
PAINT MONO (-135 1410);
FORCEPROP 0 LASTPIN (-125 1450) $PN C23
J 2
(-135 1460);
DISPLAY 0.680851 (-135 1460);
PAINT MONO (-135 1460);
FORCEPROP 0 LASTPIN (-125 1500) $PN B22
J 2
(-135 1510);
DISPLAY 0.680851 (-135 1510);
PAINT MONO (-135 1510);
FORCEPROP 0 LASTPIN (-125 1550) $PN E23
J 2
(-135 1560);
DISPLAY 0.680851 (-135 1560);
PAINT MONO (-135 1560);
FORCEPROP 0 LASTPIN (-125 1600) $PN F22
J 2
(-135 1610);
DISPLAY 0.680851 (-135 1610);
PAINT MONO (-135 1610);
FORCEPROP 0 LASTPIN (-125 1650) $PN B20
J 2
(-135 1660);
DISPLAY 0.680851 (-135 1660);
PAINT MONO (-135 1660);
FORCEPROP 0 LASTPIN (-125 1700) $PN C19
J 2
(-135 1710);
DISPLAY 0.680851 (-135 1710);
PAINT MONO (-135 1710);
FORCEPROP 0 LASTPIN (-125 1750) $PN F20
J 2
(-135 1760);
DISPLAY 0.680851 (-135 1760);
PAINT MONO (-135 1760);
FORCEPROP 0 LASTPIN (-125 1800) $PN E19
J 2
(-135 1810);
DISPLAY 0.680851 (-135 1810);
PAINT MONO (-135 1810);
FORCEPROP 0 LASTPIN (-125 1850) $PN C11
J 2
(-135 1860);
DISPLAY 0.680851 (-135 1860);
PAINT MONO (-135 1860);
FORCEPROP 0 LASTPIN (-125 1900) $PN B10
J 2
(-135 1910);
DISPLAY 0.680851 (-135 1910);
PAINT MONO (-135 1910);
FORCEPROP 0 LASTPIN (-125 1950) $PN E11
J 2
(-135 1960);
DISPLAY 0.680851 (-135 1960);
PAINT MONO (-135 1960);
FORCEPROP 0 LASTPIN (-125 2000) $PN F10
J 2
(-135 2010);
DISPLAY 0.680851 (-135 2010);
PAINT MONO (-135 2010);
FORCEPROP 0 LASTPIN (-125 2050) $PN B8
J 2
(-135 2060);
DISPLAY 0.680851 (-135 2060);
PAINT MONO (-135 2060);
FORCEPROP 0 LASTPIN (-125 2100) $PN C7
J 2
(-135 2110);
DISPLAY 0.680851 (-135 2110);
PAINT MONO (-135 2110);
FORCEPROP 0 LASTPIN (-125 2150) $PN F8
J 2
(-135 2160);
DISPLAY 0.680851 (-135 2160);
PAINT MONO (-135 2160);
FORCEPROP 0 LASTPIN (-125 2200) $PN E7
J 2
(-135 2210);
DISPLAY 0.680851 (-135 2210);
PAINT MONO (-135 2210);
FORCEPROP 0 LASTPIN (2325 2050) $PN H30
J 0
(2335 2060);
DISPLAY 0.680851 (2335 2060);
PAINT MONO (2335 2060);
FORCEPROP 0 LASTPIN (2325 2100) $PN A27
J 0
(2335 2110);
DISPLAY 0.680851 (2335 2110);
PAINT MONO (2335 2110);
FORCEPROP 0 LASTPIN (2325 2150) $PN A21
J 0
(2335 2160);
DISPLAY 0.680851 (2335 2160);
PAINT MONO (2335 2160);
FORCEPROP 0 LASTPIN (2325 2200) $PN A9
J 0
(2335 2210);
DISPLAY 0.680851 (2335 2210);
PAINT MONO (2335 2210);
FORCEPROP 0 LASTPIN (2325 2250) $PN G33
J 0
(2335 2260);
DISPLAY 0.680851 (2335 2260);
PAINT MONO (2335 2260);
FORCEPROP 0 LASTPIN (2325 2300) $PN M30
J 0
(2335 2310);
DISPLAY 0.680851 (2335 2310);
PAINT MONO (2335 2310);
FORCEPROP 0 LASTPIN (2325 2350) $PN G27
J 0
(2335 2360);
DISPLAY 0.680851 (2335 2360);
PAINT MONO (2335 2360);
FORCEPROP 0 LASTPIN (2325 2400) $PN G21
J 0
(2335 2410);
DISPLAY 0.680851 (2335 2410);
PAINT MONO (2335 2410);
FORCEPROP 0 LASTPIN (2325 2450) $PN G9
J 0
(2335 2460);
DISPLAY 0.680851 (2335 2460);
PAINT MONO (2335 2460);
FORCEPROP 0 LASTPIN (2325 2500) $PN A33
J 0
(2335 2510);
DISPLAY 0.680851 (2335 2510);
PAINT MONO (2335 2510);
FORCEPROP 0 LASTPIN (2325 2600) $PN K30
J 0
(2335 2610);
DISPLAY 0.680851 (2335 2610);
PAINT MONO (2335 2610);
FORCEPROP 0 LASTPIN (2325 2650) $PN C27
J 0
(2335 2660);
DISPLAY 0.680851 (2335 2660);
PAINT MONO (2335 2660);
FORCEPROP 0 LASTPIN (2325 2700) $PN C21
J 0
(2335 2710);
DISPLAY 0.680851 (2335 2710);
PAINT MONO (2335 2710);
FORCEPROP 0 LASTPIN (2325 2750) $PN C9
J 0
(2335 2760);
DISPLAY 0.680851 (2335 2760);
PAINT MONO (2335 2760);
FORCEPROP 0 LASTPIN (2325 2800) $PN E33
J 0
(2335 2810);
DISPLAY 0.680851 (2335 2810);
PAINT MONO (2335 2810);
FORCEPROP 0 LASTPIN (2325 2850) $PN P30
J 0
(2335 2860);
DISPLAY 0.680851 (2335 2860);
PAINT MONO (2335 2860);
FORCEPROP 0 LASTPIN (2325 2900) $PN E27
J 0
(2335 2910);
DISPLAY 0.680851 (2335 2910);
PAINT MONO (2335 2910);
FORCEPROP 0 LASTPIN (2325 2950) $PN E21
J 0
(2335 2960);
DISPLAY 0.680851 (2335 2960);
PAINT MONO (2335 2960);
FORCEPROP 0 LASTPIN (2325 3000) $PN E9
J 0
(2335 3010);
DISPLAY 0.680851 (2335 3010);
PAINT MONO (2335 3010);
FORCEPROP 0 LASTPIN (2325 3050) $PN C33
J 0
(2335 3060);
DISPLAY 0.680851 (2335 3060);
PAINT MONO (2335 3060);
FORCEPROP 0 LASTPIN (-125 250) $PN B32
J 2
(-135 260);
DISPLAY 0.680851 (-135 260);
PAINT MONO (-135 260);
FORCEPROP 0 LASTPIN (-125 300) $PN C31
J 2
(-135 310);
DISPLAY 0.680851 (-135 310);
PAINT MONO (-135 310);
FORCEPROP 0 LASTPIN (-125 350) $PN F32
J 2
(-135 360);
DISPLAY 0.680851 (-135 360);
PAINT MONO (-135 360);
FORCEPROP 0 LASTPIN (-125 400) $PN E31
J 2
(-135 410);
DISPLAY 0.680851 (-135 410);
PAINT MONO (-135 410);
FORCEPROP 0 LASTPIN (-125 450) $PN C35
J 2
(-135 460);
DISPLAY 0.680851 (-135 460);
PAINT MONO (-135 460);
FORCEPROP 0 LASTPIN (-125 500) $PN B34
J 2
(-135 510);
DISPLAY 0.680851 (-135 510);
PAINT MONO (-135 510);
FORCEPROP 0 LASTPIN (-125 550) $PN E35
J 2
(-135 560);
DISPLAY 0.680851 (-135 560);
PAINT MONO (-135 560);
FORCEPROP 0 LASTPIN (-125 600) $PN F34
J 2
(-135 610);
DISPLAY 0.680851 (-135 610);
PAINT MONO (-135 610);
FORCEPROP 0 LASTPIN (2325 1050) $PN G39
J 0
(2335 1060);
DISPLAY 0.680851 (2335 1060);
PAINT MONO (2335 1060);
FORCEPROP 0 LASTPIN (2325 750) $PN C54
J 0
(2335 760);
DISPLAY 0.680851 (2335 760);
PAINT MONO (2335 760);
FORCEPROP 0 LASTPIN (2325 800) $PN B53
J 0
(2335 810);
DISPLAY 0.680851 (2335 810);
PAINT MONO (2335 810);
FORCEPROP 0 LASTPIN (2325 850) $PN E54
J 0
(2335 860);
DISPLAY 0.680851 (2335 860);
PAINT MONO (2335 860);
FORCEPROP 0 LASTPIN (2325 900) $PN F53
J 0
(2335 910);
DISPLAY 0.680851 (2335 910);
PAINT MONO (2335 910);
FORCEPROP 0 LASTPIN (2325 450) $PN B38
J 0
(2335 460);
DISPLAY 0.680851 (2335 460);
PAINT MONO (2335 460);
FORCEPROP 0 LASTPIN (2325 500) $PN C37
J 0
(2335 510);
DISPLAY 0.680851 (2335 510);
PAINT MONO (2335 510);
FORCEPROP 0 LASTPIN (2325 550) $PN F38
J 0
(2335 560);
DISPLAY 0.680851 (2335 560);
PAINT MONO (2335 560);
FORCEPROP 0 LASTPIN (2325 600) $PN E37
J 0
(2335 610);
DISPLAY 0.680851 (2335 610);
PAINT MONO (2335 610);
FORCEPROP 2 LAST CDS_LIB pure_quanta
J 0
(1100 2100);
DISPLAY INVISIBLE (1100 2100);
FORCEPROP 1 LAST NEEDS_NO_SIZE TRUE
J 0
(1100 2100);
DISPLAY 0.723404 (1100 2100);
PAINT GREEN (1100 2100);
DISPLAY INVISIBLE (1100 2100);
FORCEPROP 1 LAST CDS_LMAN_SYM_OUTLINE -1100,2250,1050,-2250
J 0
(1100 2100);
DISPLAY 0.468085 (1100 2100);
PAINT GREEN (1100 2100);
DISPLAY INVISIBLE (1100 2100);
FORCEPROP 2 LAST CDS_LOCATION U2
J 0
(0 4675);
DISPLAY 1.021277 (0 4675);
DISPLAY INVISIBLE (0 4675);
FORCEPROP 0 LAST $SEC 8
J 0
(0 4675);
DISPLAY 0.680851 (0 4675);
PAINT MONO (0 4675);
DISPLAY INVISIBLE (0 4675);
FORCEPROP 2 LAST CDS_SEC 8
J 0
(0 4675);
DISPLAY 1.021277 (0 4675);
DISPLAY INVISIBLE (0 4675);
FORCEPROP 1 LAST PATH I1
J 0
(1100 2100);
DISPLAY 0.723404 (1100 2100);
PAINT GREEN (1100 2100);
DISPLAY INVISIBLE (1100 2100);
FORCEADD TAP..1
R 2
(-625 3500);
FORCEPROP 3 LASTPIN (-575 3500) SIG_NAME M_A_CPU0_SA_DQ<17>
J 0
(-565 3510);
DISPLAY 0.659574 (-565 3510);
PAINT MONO (-565 3510);
DISPLAY INVISIBLE (-565 3510);
FORCEPROP 1 LASTPIN (-575 3500) BN 17
J 2
(-563 3508);
DISPLAY 0.680851 (-563 3508);
PAINT GREEN (-563 3508);
FORCEPROP 2 LAST CDS_LIB standard
J 0
(-625 3500);
DISPLAY INVISIBLE (-625 3500);
FORCEPROP 1 LAST BODY_TYPE PLUMBING
J 2
(-625 3550);
DISPLAY 0.872340 (-625 3550);
PAINT GREEN (-625 3550);
DISPLAY INVISIBLE (-625 3550);
FORCEPROP 1 LAST HDL_TAP TRUE
J 2
(-950 3375);
DISPLAY 0.872340 (-950 3375);
DISPLAY INVISIBLE (-950 3375);
FORCEPROP 1 LAST PATH I10
J 2
(-623 3500);
DISPLAY 0.872340 (-623 3500);
PAINT GREEN (-623 3500);
DISPLAY INVISIBLE (-623 3500);
FORCEADD TAP..1
(2800 3500);
FORCEPROP 3 LASTPIN (2750 3500) SIG_NAME M_A_CPU0_SA_DQS_DN<6>
J 0
(2760 3510);
DISPLAY 0.659574 (2760 3510);
PAINT MONO (2760 3510);
DISPLAY INVISIBLE (2760 3510);
FORCEPROP 1 LASTPIN (2750 3500) BN 6
J 0
(2738 3508);
DISPLAY 0.680851 (2738 3508);
PAINT GREEN (2738 3508);
FORCEPROP 2 LAST CDS_LIB standard
J 0
(2800 3500);
DISPLAY INVISIBLE (2800 3500);
FORCEPROP 1 LAST BODY_TYPE PLUMBING
J 0
(2800 3550);
DISPLAY 0.872340 (2800 3550);
PAINT GREEN (2800 3550);
DISPLAY INVISIBLE (2800 3550);
FORCEPROP 1 LAST HDL_TAP TRUE
J 0
(3125 3375);
DISPLAY 0.872340 (3125 3375);
DISPLAY INVISIBLE (3125 3375);
FORCEPROP 1 LAST PATH I100
J 0
(2798 3500);
DISPLAY 0.872340 (2798 3500);
PAINT GREEN (2798 3500);
DISPLAY INVISIBLE (2798 3500);
FORCEADD TAP..1
(2800 3350);
FORCEPROP 3 LASTPIN (2750 3350) SIG_NAME M_A_CPU0_SA_DQS_DN<3>
J 0
(2760 3360);
DISPLAY 0.659574 (2760 3360);
PAINT MONO (2760 3360);
DISPLAY INVISIBLE (2760 3360);
FORCEPROP 1 LASTPIN (2750 3350) BN 3
J 0
(2738 3358);
DISPLAY 0.680851 (2738 3358);
PAINT GREEN (2738 3358);
FORCEPROP 2 LAST CDS_LIB standard
J 0
(2800 3350);
DISPLAY INVISIBLE (2800 3350);
FORCEPROP 1 LAST BODY_TYPE PLUMBING
J 0
(2800 3400);
DISPLAY 0.872340 (2800 3400);
PAINT GREEN (2800 3400);
DISPLAY INVISIBLE (2800 3400);
FORCEPROP 1 LAST HDL_TAP TRUE
J 0
(3125 3225);
DISPLAY 0.872340 (3125 3225);
DISPLAY INVISIBLE (3125 3225);
FORCEPROP 1 LAST PATH I101
J 0
(2798 3350);
DISPLAY 0.872340 (2798 3350);
PAINT GREEN (2798 3350);
DISPLAY INVISIBLE (2798 3350);
FORCEADD TAP..1
(2800 3300);
FORCEPROP 3 LASTPIN (2750 3300) SIG_NAME M_A_CPU0_SA_DQS_DN<2>
J 0
(2760 3310);
DISPLAY 0.659574 (2760 3310);
PAINT MONO (2760 3310);
DISPLAY INVISIBLE (2760 3310);
FORCEPROP 1 LASTPIN (2750 3300) BN 2
J 0
(2738 3308);
DISPLAY 0.680851 (2738 3308);
PAINT GREEN (2738 3308);
FORCEPROP 2 LAST CDS_LIB standard
J 0
(2800 3300);
DISPLAY INVISIBLE (2800 3300);
FORCEPROP 1 LAST BODY_TYPE PLUMBING
J 0
(2800 3350);
DISPLAY 0.872340 (2800 3350);
PAINT GREEN (2800 3350);
DISPLAY INVISIBLE (2800 3350);
FORCEPROP 1 LAST HDL_TAP TRUE
J 0
(3125 3175);
DISPLAY 0.872340 (3125 3175);
DISPLAY INVISIBLE (3125 3175);
FORCEPROP 1 LAST PATH I102
J 0
(2798 3300);
DISPLAY 0.872340 (2798 3300);
PAINT GREEN (2798 3300);
DISPLAY INVISIBLE (2798 3300);
FORCEADD TAP..1
(2800 3400);
FORCEPROP 3 LASTPIN (2750 3400) SIG_NAME M_A_CPU0_SA_DQS_DN<4>
J 0
(2760 3410);
DISPLAY 0.659574 (2760 3410);
PAINT MONO (2760 3410);
DISPLAY INVISIBLE (2760 3410);
FORCEPROP 1 LASTPIN (2750 3400) BN 4
J 0
(2738 3408);
DISPLAY 0.680851 (2738 3408);
PAINT GREEN (2738 3408);
FORCEPROP 2 LAST CDS_LIB standard
J 0
(2800 3400);
DISPLAY INVISIBLE (2800 3400);
FORCEPROP 1 LAST BODY_TYPE PLUMBING
J 0
(2800 3450);
DISPLAY 0.872340 (2800 3450);
PAINT GREEN (2800 3450);
DISPLAY INVISIBLE (2800 3450);
FORCEPROP 1 LAST HDL_TAP TRUE
J 0
(3125 3275);
DISPLAY 0.872340 (3125 3275);
DISPLAY INVISIBLE (3125 3275);
FORCEPROP 1 LAST PATH I103
J 0
(2798 3400);
DISPLAY 0.872340 (2798 3400);
PAINT GREEN (2798 3400);
DISPLAY INVISIBLE (2798 3400);
FORCEADD TAP..1
(2800 3250);
FORCEPROP 3 LASTPIN (2750 3250) SIG_NAME M_A_CPU0_SA_DQS_DN<1>
J 0
(2760 3260);
DISPLAY 0.659574 (2760 3260);
PAINT MONO (2760 3260);
DISPLAY INVISIBLE (2760 3260);
FORCEPROP 1 LASTPIN (2750 3250) BN 1
J 0
(2738 3258);
DISPLAY 0.680851 (2738 3258);
PAINT GREEN (2738 3258);
FORCEPROP 2 LAST CDS_LIB standard
J 0
(2800 3250);
DISPLAY INVISIBLE (2800 3250);
FORCEPROP 1 LAST BODY_TYPE PLUMBING
J 0
(2800 3300);
DISPLAY 0.872340 (2800 3300);
PAINT GREEN (2800 3300);
DISPLAY INVISIBLE (2800 3300);
FORCEPROP 1 LAST HDL_TAP TRUE
J 0
(3125 3125);
DISPLAY 0.872340 (3125 3125);
DISPLAY INVISIBLE (3125 3125);
FORCEPROP 1 LAST PATH I104
J 0
(2798 3250);
DISPLAY 0.872340 (2798 3250);
PAINT GREEN (2798 3250);
DISPLAY INVISIBLE (2798 3250);
FORCEADD OFFPAGE..3
(3900 3075);
FORCEPROP 2 LAST $XR1 83 
J 0
(4204 3075);
DISPLAY 0.638298 (4204 3075);
PAINT MONO (4204 3075);
FORCEPROP 2 LAST $XR0 82 
J 0
(4114 3075);
DISPLAY 0.638298 (4114 3075);
PAINT MONO (4114 3075);
FORCEPROP 2 LAST CDS_LIB standard
J 2
(3900 3075);
DISPLAY INVISIBLE (3900 3075);
FORCEPROP 1 LAST OFFPAGE TRUE
J 0
(4225 2950);
DISPLAY 0.872340 (4225 2950);
DISPLAY INVISIBLE (4225 2950);
FORCEPROP 1 LAST COMMENT_BODY TRUE
J 0
(3850 2975);
DISPLAY 0.872340 (3850 2975);
PAINT GREEN (3850 2975);
DISPLAY INVISIBLE (3850 2975);
FORCEPROP 2 LAST PATH I105
J 0
(4100 3150);
DISPLAY 1.021277 (4100 3150);
DISPLAY INVISIBLE (4100 3150);
FORCEADD TAP..1
(2800 3050);
FORCEPROP 3 LASTPIN (2750 3050) SIG_NAME M_A_CPU0_SB_DQS_DP<9>
J 0
(2760 3060);
DISPLAY 0.659574 (2760 3060);
PAINT MONO (2760 3060);
DISPLAY INVISIBLE (2760 3060);
FORCEPROP 1 LASTPIN (2750 3050) BN 9
J 0
(2738 3058);
DISPLAY 0.680851 (2738 3058);
PAINT GREEN (2738 3058);
FORCEPROP 2 LAST CDS_LIB standard
J 0
(2800 3050);
DISPLAY INVISIBLE (2800 3050);
FORCEPROP 1 LAST BODY_TYPE PLUMBING
J 0
(2800 3100);
DISPLAY 0.872340 (2800 3100);
PAINT GREEN (2800 3100);
DISPLAY INVISIBLE (2800 3100);
FORCEPROP 1 LAST HDL_TAP TRUE
J 0
(3125 2925);
DISPLAY 0.872340 (3125 2925);
DISPLAY INVISIBLE (3125 2925);
FORCEPROP 1 LAST PATH I106
J 0
(2798 3050);
DISPLAY 0.872340 (2798 3050);
PAINT GREEN (2798 3050);
DISPLAY INVISIBLE (2798 3050);
FORCEADD TAP..1
(2800 3000);
FORCEPROP 3 LASTPIN (2750 3000) SIG_NAME M_A_CPU0_SB_DQS_DP<8>
J 0
(2760 3010);
DISPLAY 0.659574 (2760 3010);
PAINT MONO (2760 3010);
DISPLAY INVISIBLE (2760 3010);
FORCEPROP 1 LASTPIN (2750 3000) BN 8
J 0
(2738 3008);
DISPLAY 0.680851 (2738 3008);
PAINT GREEN (2738 3008);
FORCEPROP 2 LAST CDS_LIB standard
J 0
(2800 3000);
DISPLAY INVISIBLE (2800 3000);
FORCEPROP 1 LAST BODY_TYPE PLUMBING
J 0
(2800 3050);
DISPLAY 0.872340 (2800 3050);
PAINT GREEN (2800 3050);
DISPLAY INVISIBLE (2800 3050);
FORCEPROP 1 LAST HDL_TAP TRUE
J 0
(3125 2875);
DISPLAY 0.872340 (3125 2875);
DISPLAY INVISIBLE (3125 2875);
FORCEPROP 1 LAST PATH I107
J 0
(2798 3000);
DISPLAY 0.872340 (2798 3000);
PAINT GREEN (2798 3000);
DISPLAY INVISIBLE (2798 3000);
FORCEADD TAP..1
(2800 2950);
FORCEPROP 3 LASTPIN (2750 2950) SIG_NAME M_A_CPU0_SB_DQS_DP<7>
J 0
(2760 2960);
DISPLAY 0.659574 (2760 2960);
PAINT MONO (2760 2960);
DISPLAY INVISIBLE (2760 2960);
FORCEPROP 1 LASTPIN (2750 2950) BN 7
J 0
(2738 2958);
DISPLAY 0.680851 (2738 2958);
PAINT GREEN (2738 2958);
FORCEPROP 2 LAST CDS_LIB standard
J 0
(2800 2950);
DISPLAY INVISIBLE (2800 2950);
FORCEPROP 1 LAST BODY_TYPE PLUMBING
J 0
(2800 3000);
DISPLAY 0.872340 (2800 3000);
PAINT GREEN (2800 3000);
DISPLAY INVISIBLE (2800 3000);
FORCEPROP 1 LAST HDL_TAP TRUE
J 0
(3125 2825);
DISPLAY 0.872340 (3125 2825);
DISPLAY INVISIBLE (3125 2825);
FORCEPROP 1 LAST PATH I108
J 0
(2798 2950);
DISPLAY 0.872340 (2798 2950);
PAINT GREEN (2798 2950);
DISPLAY INVISIBLE (2798 2950);
FORCEADD OFFPAGE..3
(3900 2525);
FORCEPROP 2 LAST $XR1 83 
J 0
(4204 2525);
DISPLAY 0.638298 (4204 2525);
PAINT MONO (4204 2525);
FORCEPROP 2 LAST $XR0 82 
J 0
(4114 2525);
DISPLAY 0.638298 (4114 2525);
PAINT MONO (4114 2525);
FORCEPROP 2 LAST CDS_LIB standard
J 2
(3900 2525);
DISPLAY INVISIBLE (3900 2525);
FORCEPROP 1 LAST OFFPAGE TRUE
J 0
(4225 2400);
DISPLAY 0.872340 (4225 2400);
DISPLAY INVISIBLE (4225 2400);
FORCEPROP 1 LAST COMMENT_BODY TRUE
J 0
(3850 2425);
DISPLAY 0.872340 (3850 2425);
PAINT GREEN (3850 2425);
DISPLAY INVISIBLE (3850 2425);
FORCEPROP 2 LAST PATH I109
J 0
(4100 2600);
DISPLAY 1.021277 (4100 2600);
DISPLAY INVISIBLE (4100 2600);
FORCEADD TAP..1
R 2
(-625 3550);
FORCEPROP 3 LASTPIN (-575 3550) SIG_NAME M_A_CPU0_SA_DQ<18>
J 0
(-565 3560);
DISPLAY 0.659574 (-565 3560);
PAINT MONO (-565 3560);
DISPLAY INVISIBLE (-565 3560);
FORCEPROP 1 LASTPIN (-575 3550) BN 18
J 2
(-563 3558);
DISPLAY 0.680851 (-563 3558);
PAINT GREEN (-563 3558);
FORCEPROP 2 LAST CDS_LIB standard
J 0
(-625 3550);
DISPLAY INVISIBLE (-625 3550);
FORCEPROP 1 LAST BODY_TYPE PLUMBING
J 2
(-625 3600);
DISPLAY 0.872340 (-625 3600);
PAINT GREEN (-625 3600);
DISPLAY INVISIBLE (-625 3600);
FORCEPROP 1 LAST HDL_TAP TRUE
J 2
(-950 3425);
DISPLAY 0.872340 (-950 3425);
DISPLAY INVISIBLE (-950 3425);
FORCEPROP 1 LAST PATH I11
J 2
(-623 3550);
DISPLAY 0.872340 (-623 3550);
PAINT GREEN (-623 3550);
DISPLAY INVISIBLE (-623 3550);
FORCEADD TAP..1
(2800 2850);
FORCEPROP 3 LASTPIN (2750 2850) SIG_NAME M_A_CPU0_SB_DQS_DP<5>
J 0
(2760 2860);
DISPLAY 0.659574 (2760 2860);
PAINT MONO (2760 2860);
DISPLAY INVISIBLE (2760 2860);
FORCEPROP 1 LASTPIN (2750 2850) BN 5
J 0
(2738 2858);
DISPLAY 0.680851 (2738 2858);
PAINT GREEN (2738 2858);
FORCEPROP 2 LAST CDS_LIB standard
J 0
(2800 2850);
DISPLAY INVISIBLE (2800 2850);
FORCEPROP 1 LAST BODY_TYPE PLUMBING
J 0
(2800 2900);
DISPLAY 0.872340 (2800 2900);
PAINT GREEN (2800 2900);
DISPLAY INVISIBLE (2800 2900);
FORCEPROP 1 LAST HDL_TAP TRUE
J 0
(3125 2725);
DISPLAY 0.872340 (3125 2725);
DISPLAY INVISIBLE (3125 2725);
FORCEPROP 1 LAST PATH I110
J 0
(2798 2850);
DISPLAY 0.872340 (2798 2850);
PAINT GREEN (2798 2850);
DISPLAY INVISIBLE (2798 2850);
FORCEADD TAP..1
(2800 2900);
FORCEPROP 3 LASTPIN (2750 2900) SIG_NAME M_A_CPU0_SB_DQS_DP<6>
J 0
(2760 2910);
DISPLAY 0.659574 (2760 2910);
PAINT MONO (2760 2910);
DISPLAY INVISIBLE (2760 2910);
FORCEPROP 1 LASTPIN (2750 2900) BN 6
J 0
(2738 2908);
DISPLAY 0.680851 (2738 2908);
PAINT GREEN (2738 2908);
FORCEPROP 2 LAST CDS_LIB standard
J 0
(2800 2900);
DISPLAY INVISIBLE (2800 2900);
FORCEPROP 1 LAST BODY_TYPE PLUMBING
J 0
(2800 2950);
DISPLAY 0.872340 (2800 2950);
PAINT GREEN (2800 2950);
DISPLAY INVISIBLE (2800 2950);
FORCEPROP 1 LAST HDL_TAP TRUE
J 0
(3125 2775);
DISPLAY 0.872340 (3125 2775);
DISPLAY INVISIBLE (3125 2775);
FORCEPROP 1 LAST PATH I111
J 0
(2798 2900);
DISPLAY 0.872340 (2798 2900);
PAINT GREEN (2798 2900);
DISPLAY INVISIBLE (2798 2900);
FORCEADD TAP..1
(2800 2750);
FORCEPROP 3 LASTPIN (2750 2750) SIG_NAME M_A_CPU0_SB_DQS_DP<3>
J 0
(2760 2760);
DISPLAY 0.659574 (2760 2760);
PAINT MONO (2760 2760);
DISPLAY INVISIBLE (2760 2760);
FORCEPROP 1 LASTPIN (2750 2750) BN 3
J 0
(2738 2758);
DISPLAY 0.680851 (2738 2758);
PAINT GREEN (2738 2758);
FORCEPROP 2 LAST CDS_LIB standard
J 0
(2800 2750);
DISPLAY INVISIBLE (2800 2750);
FORCEPROP 1 LAST BODY_TYPE PLUMBING
J 0
(2800 2800);
DISPLAY 0.872340 (2800 2800);
PAINT GREEN (2800 2800);
DISPLAY INVISIBLE (2800 2800);
FORCEPROP 1 LAST HDL_TAP TRUE
J 0
(3125 2625);
DISPLAY 0.872340 (3125 2625);
DISPLAY INVISIBLE (3125 2625);
FORCEPROP 1 LAST PATH I112
J 0
(2798 2750);
DISPLAY 0.872340 (2798 2750);
PAINT GREEN (2798 2750);
DISPLAY INVISIBLE (2798 2750);
FORCEADD TAP..1
(2800 2700);
FORCEPROP 3 LASTPIN (2750 2700) SIG_NAME M_A_CPU0_SB_DQS_DP<2>
J 0
(2760 2710);
DISPLAY 0.659574 (2760 2710);
PAINT MONO (2760 2710);
DISPLAY INVISIBLE (2760 2710);
FORCEPROP 1 LASTPIN (2750 2700) BN 2
J 0
(2738 2708);
DISPLAY 0.680851 (2738 2708);
PAINT GREEN (2738 2708);
FORCEPROP 2 LAST CDS_LIB standard
J 0
(2800 2700);
DISPLAY INVISIBLE (2800 2700);
FORCEPROP 1 LAST BODY_TYPE PLUMBING
J 0
(2800 2750);
DISPLAY 0.872340 (2800 2750);
PAINT GREEN (2800 2750);
DISPLAY INVISIBLE (2800 2750);
FORCEPROP 1 LAST HDL_TAP TRUE
J 0
(3125 2575);
DISPLAY 0.872340 (3125 2575);
DISPLAY INVISIBLE (3125 2575);
FORCEPROP 1 LAST PATH I113
J 0
(2798 2700);
DISPLAY 0.872340 (2798 2700);
PAINT GREEN (2798 2700);
DISPLAY INVISIBLE (2798 2700);
FORCEADD TAP..1
(2800 2800);
FORCEPROP 3 LASTPIN (2750 2800) SIG_NAME M_A_CPU0_SB_DQS_DP<4>
J 0
(2760 2810);
DISPLAY 0.659574 (2760 2810);
PAINT MONO (2760 2810);
DISPLAY INVISIBLE (2760 2810);
FORCEPROP 1 LASTPIN (2750 2800) BN 4
J 0
(2738 2808);
DISPLAY 0.680851 (2738 2808);
PAINT GREEN (2738 2808);
FORCEPROP 2 LAST CDS_LIB standard
J 0
(2800 2800);
DISPLAY INVISIBLE (2800 2800);
FORCEPROP 1 LAST BODY_TYPE PLUMBING
J 0
(2800 2850);
DISPLAY 0.872340 (2800 2850);
PAINT GREEN (2800 2850);
DISPLAY INVISIBLE (2800 2850);
FORCEPROP 1 LAST HDL_TAP TRUE
J 0
(3125 2675);
DISPLAY 0.872340 (3125 2675);
DISPLAY INVISIBLE (3125 2675);
FORCEPROP 1 LAST PATH I114
J 0
(2798 2800);
DISPLAY 0.872340 (2798 2800);
PAINT GREEN (2798 2800);
DISPLAY INVISIBLE (2798 2800);
FORCEADD TAP..1
(2800 2600);
FORCEPROP 3 LASTPIN (2750 2600) SIG_NAME M_A_CPU0_SB_DQS_DP<0>
J 0
(2760 2610);
DISPLAY 0.659574 (2760 2610);
PAINT MONO (2760 2610);
DISPLAY INVISIBLE (2760 2610);
FORCEPROP 1 LASTPIN (2750 2600) BN 0
J 0
(2738 2608);
DISPLAY 0.680851 (2738 2608);
PAINT GREEN (2738 2608);
FORCEPROP 2 LAST CDS_LIB standard
J 0
(2800 2600);
DISPLAY INVISIBLE (2800 2600);
FORCEPROP 1 LAST BODY_TYPE PLUMBING
J 0
(2800 2650);
DISPLAY 0.872340 (2800 2650);
PAINT GREEN (2800 2650);
DISPLAY INVISIBLE (2800 2650);
FORCEPROP 1 LAST HDL_TAP TRUE
J 0
(3125 2475);
DISPLAY 0.872340 (3125 2475);
DISPLAY INVISIBLE (3125 2475);
FORCEPROP 1 LAST PATH I115
J 0
(2798 2600);
DISPLAY 0.872340 (2798 2600);
PAINT GREEN (2798 2600);
DISPLAY INVISIBLE (2798 2600);
FORCEADD TAP..1
(2800 2650);
FORCEPROP 3 LASTPIN (2750 2650) SIG_NAME M_A_CPU0_SB_DQS_DP<1>
J 0
(2760 2660);
DISPLAY 0.659574 (2760 2660);
PAINT MONO (2760 2660);
DISPLAY INVISIBLE (2760 2660);
FORCEPROP 1 LASTPIN (2750 2650) BN 1
J 0
(2738 2658);
DISPLAY 0.680851 (2738 2658);
PAINT GREEN (2738 2658);
FORCEPROP 2 LAST CDS_LIB standard
J 0
(2800 2650);
DISPLAY INVISIBLE (2800 2650);
FORCEPROP 1 LAST BODY_TYPE PLUMBING
J 0
(2800 2700);
DISPLAY 0.872340 (2800 2700);
PAINT GREEN (2800 2700);
DISPLAY INVISIBLE (2800 2700);
FORCEPROP 1 LAST HDL_TAP TRUE
J 0
(3125 2525);
DISPLAY 0.872340 (3125 2525);
DISPLAY INVISIBLE (3125 2525);
FORCEPROP 1 LAST PATH I116
J 0
(2798 2650);
DISPLAY 0.872340 (2798 2650);
PAINT GREEN (2798 2650);
DISPLAY INVISIBLE (2798 2650);
FORCEADD TAP..1
(2800 2450);
FORCEPROP 3 LASTPIN (2750 2450) SIG_NAME M_A_CPU0_SB_DQS_DN<8>
J 0
(2760 2460);
DISPLAY 0.659574 (2760 2460);
PAINT MONO (2760 2460);
DISPLAY INVISIBLE (2760 2460);
FORCEPROP 1 LASTPIN (2750 2450) BN 8
J 0
(2738 2458);
DISPLAY 0.680851 (2738 2458);
PAINT GREEN (2738 2458);
FORCEPROP 2 LAST CDS_LIB standard
J 0
(2800 2450);
DISPLAY INVISIBLE (2800 2450);
FORCEPROP 1 LAST BODY_TYPE PLUMBING
J 0
(2800 2500);
DISPLAY 0.872340 (2800 2500);
PAINT GREEN (2800 2500);
DISPLAY INVISIBLE (2800 2500);
FORCEPROP 1 LAST HDL_TAP TRUE
J 0
(3125 2325);
DISPLAY 0.872340 (3125 2325);
DISPLAY INVISIBLE (3125 2325);
FORCEPROP 1 LAST PATH I117
J 0
(2798 2450);
DISPLAY 0.872340 (2798 2450);
PAINT GREEN (2798 2450);
DISPLAY INVISIBLE (2798 2450);
FORCEADD TAP..1
(2800 2500);
FORCEPROP 3 LASTPIN (2750 2500) SIG_NAME M_A_CPU0_SB_DQS_DN<9>
J 0
(2760 2510);
DISPLAY 0.659574 (2760 2510);
PAINT MONO (2760 2510);
DISPLAY INVISIBLE (2760 2510);
FORCEPROP 1 LASTPIN (2750 2500) BN 9
J 0
(2738 2508);
DISPLAY 0.680851 (2738 2508);
PAINT GREEN (2738 2508);
FORCEPROP 2 LAST CDS_LIB standard
J 0
(2800 2500);
DISPLAY INVISIBLE (2800 2500);
FORCEPROP 1 LAST BODY_TYPE PLUMBING
J 0
(2800 2550);
DISPLAY 0.872340 (2800 2550);
PAINT GREEN (2800 2550);
DISPLAY INVISIBLE (2800 2550);
FORCEPROP 1 LAST HDL_TAP TRUE
J 0
(3125 2375);
DISPLAY 0.872340 (3125 2375);
DISPLAY INVISIBLE (3125 2375);
FORCEPROP 1 LAST PATH I118
J 0
(2798 2500);
DISPLAY 0.872340 (2798 2500);
PAINT GREEN (2798 2500);
DISPLAY INVISIBLE (2798 2500);
FORCEADD TAP..1
(2800 2400);
FORCEPROP 3 LASTPIN (2750 2400) SIG_NAME M_A_CPU0_SB_DQS_DN<7>
J 0
(2760 2410);
DISPLAY 0.659574 (2760 2410);
PAINT MONO (2760 2410);
DISPLAY INVISIBLE (2760 2410);
FORCEPROP 1 LASTPIN (2750 2400) BN 7
J 0
(2738 2408);
DISPLAY 0.680851 (2738 2408);
PAINT GREEN (2738 2408);
FORCEPROP 2 LAST CDS_LIB standard
J 0
(2800 2400);
DISPLAY INVISIBLE (2800 2400);
FORCEPROP 1 LAST BODY_TYPE PLUMBING
J 0
(2800 2450);
DISPLAY 0.872340 (2800 2450);
PAINT GREEN (2800 2450);
DISPLAY INVISIBLE (2800 2450);
FORCEPROP 1 LAST HDL_TAP TRUE
J 0
(3125 2275);
DISPLAY 0.872340 (3125 2275);
DISPLAY INVISIBLE (3125 2275);
FORCEPROP 1 LAST PATH I119
J 0
(2798 2400);
DISPLAY 0.872340 (2798 2400);
PAINT GREEN (2798 2400);
DISPLAY INVISIBLE (2798 2400);
FORCEADD TAP..1
R 2
(-625 3600);
FORCEPROP 3 LASTPIN (-575 3600) SIG_NAME M_A_CPU0_SA_DQ<19>
J 0
(-565 3610);
DISPLAY 0.659574 (-565 3610);
PAINT MONO (-565 3610);
DISPLAY INVISIBLE (-565 3610);
FORCEPROP 1 LASTPIN (-575 3600) BN 19
J 2
(-563 3608);
DISPLAY 0.680851 (-563 3608);
PAINT GREEN (-563 3608);
FORCEPROP 2 LAST CDS_LIB standard
J 0
(-625 3600);
DISPLAY INVISIBLE (-625 3600);
FORCEPROP 1 LAST BODY_TYPE PLUMBING
J 2
(-625 3650);
DISPLAY 0.872340 (-625 3650);
PAINT GREEN (-625 3650);
DISPLAY INVISIBLE (-625 3650);
FORCEPROP 1 LAST HDL_TAP TRUE
J 2
(-950 3475);
DISPLAY 0.872340 (-950 3475);
DISPLAY INVISIBLE (-950 3475);
FORCEPROP 1 LAST PATH I12
J 2
(-623 3600);
DISPLAY 0.872340 (-623 3600);
PAINT GREEN (-623 3600);
DISPLAY INVISIBLE (-623 3600);
FORCEADD TAP..1
(2800 2350);
FORCEPROP 3 LASTPIN (2750 2350) SIG_NAME M_A_CPU0_SB_DQS_DN<6>
J 0
(2760 2360);
DISPLAY 0.659574 (2760 2360);
PAINT MONO (2760 2360);
DISPLAY INVISIBLE (2760 2360);
FORCEPROP 1 LASTPIN (2750 2350) BN 6
J 0
(2738 2358);
DISPLAY 0.680851 (2738 2358);
PAINT GREEN (2738 2358);
FORCEPROP 2 LAST CDS_LIB standard
J 0
(2800 2350);
DISPLAY INVISIBLE (2800 2350);
FORCEPROP 1 LAST BODY_TYPE PLUMBING
J 0
(2800 2400);
DISPLAY 0.872340 (2800 2400);
PAINT GREEN (2800 2400);
DISPLAY INVISIBLE (2800 2400);
FORCEPROP 1 LAST HDL_TAP TRUE
J 0
(3125 2225);
DISPLAY 0.872340 (3125 2225);
DISPLAY INVISIBLE (3125 2225);
FORCEPROP 1 LAST PATH I120
J 0
(2798 2350);
DISPLAY 0.872340 (2798 2350);
PAINT GREEN (2798 2350);
DISPLAY INVISIBLE (2798 2350);
FORCEADD TAP..1
(2800 2200);
FORCEPROP 3 LASTPIN (2750 2200) SIG_NAME M_A_CPU0_SB_DQS_DN<3>
J 0
(2760 2210);
DISPLAY 0.659574 (2760 2210);
PAINT MONO (2760 2210);
DISPLAY INVISIBLE (2760 2210);
FORCEPROP 1 LASTPIN (2750 2200) BN 3
J 0
(2738 2208);
DISPLAY 0.680851 (2738 2208);
PAINT GREEN (2738 2208);
FORCEPROP 2 LAST CDS_LIB standard
J 0
(2800 2200);
DISPLAY INVISIBLE (2800 2200);
FORCEPROP 1 LAST BODY_TYPE PLUMBING
J 0
(2800 2250);
DISPLAY 0.872340 (2800 2250);
PAINT GREEN (2800 2250);
DISPLAY INVISIBLE (2800 2250);
FORCEPROP 1 LAST HDL_TAP TRUE
J 0
(3125 2075);
DISPLAY 0.872340 (3125 2075);
DISPLAY INVISIBLE (3125 2075);
FORCEPROP 1 LAST PATH I121
J 0
(2798 2200);
DISPLAY 0.872340 (2798 2200);
PAINT GREEN (2798 2200);
DISPLAY INVISIBLE (2798 2200);
FORCEADD TAP..1
(2800 2300);
FORCEPROP 3 LASTPIN (2750 2300) SIG_NAME M_A_CPU0_SB_DQS_DN<5>
J 0
(2760 2310);
DISPLAY 0.659574 (2760 2310);
PAINT MONO (2760 2310);
DISPLAY INVISIBLE (2760 2310);
FORCEPROP 1 LASTPIN (2750 2300) BN 5
J 0
(2738 2308);
DISPLAY 0.680851 (2738 2308);
PAINT GREEN (2738 2308);
FORCEPROP 2 LAST CDS_LIB standard
J 0
(2800 2300);
DISPLAY INVISIBLE (2800 2300);
FORCEPROP 1 LAST BODY_TYPE PLUMBING
J 0
(2800 2350);
DISPLAY 0.872340 (2800 2350);
PAINT GREEN (2800 2350);
DISPLAY INVISIBLE (2800 2350);
FORCEPROP 1 LAST HDL_TAP TRUE
J 0
(3125 2175);
DISPLAY 0.872340 (3125 2175);
DISPLAY INVISIBLE (3125 2175);
FORCEPROP 1 LAST PATH I122
J 0
(2798 2300);
DISPLAY 0.872340 (2798 2300);
PAINT GREEN (2798 2300);
DISPLAY INVISIBLE (2798 2300);
FORCEADD TAP..1
(2800 2250);
FORCEPROP 3 LASTPIN (2750 2250) SIG_NAME M_A_CPU0_SB_DQS_DN<4>
J 0
(2760 2260);
DISPLAY 0.659574 (2760 2260);
PAINT MONO (2760 2260);
DISPLAY INVISIBLE (2760 2260);
FORCEPROP 1 LASTPIN (2750 2250) BN 4
J 0
(2738 2258);
DISPLAY 0.680851 (2738 2258);
PAINT GREEN (2738 2258);
FORCEPROP 2 LAST CDS_LIB standard
J 0
(2800 2250);
DISPLAY INVISIBLE (2800 2250);
FORCEPROP 1 LAST BODY_TYPE PLUMBING
J 0
(2800 2300);
DISPLAY 0.872340 (2800 2300);
PAINT GREEN (2800 2300);
DISPLAY INVISIBLE (2800 2300);
FORCEPROP 1 LAST HDL_TAP TRUE
J 0
(3125 2125);
DISPLAY 0.872340 (3125 2125);
DISPLAY INVISIBLE (3125 2125);
FORCEPROP 1 LAST PATH I123
J 0
(2798 2250);
DISPLAY 0.872340 (2798 2250);
PAINT GREEN (2798 2250);
DISPLAY INVISIBLE (2798 2250);
FORCEADD TAP..1
(2800 2100);
FORCEPROP 3 LASTPIN (2750 2100) SIG_NAME M_A_CPU0_SB_DQS_DN<1>
J 0
(2760 2110);
DISPLAY 0.659574 (2760 2110);
PAINT MONO (2760 2110);
DISPLAY INVISIBLE (2760 2110);
FORCEPROP 1 LASTPIN (2750 2100) BN 1
J 0
(2738 2108);
DISPLAY 0.680851 (2738 2108);
PAINT GREEN (2738 2108);
FORCEPROP 2 LAST CDS_LIB standard
J 0
(2800 2100);
DISPLAY INVISIBLE (2800 2100);
FORCEPROP 1 LAST BODY_TYPE PLUMBING
J 0
(2800 2150);
DISPLAY 0.872340 (2800 2150);
PAINT GREEN (2800 2150);
DISPLAY INVISIBLE (2800 2150);
FORCEPROP 1 LAST HDL_TAP TRUE
J 0
(3125 1975);
DISPLAY 0.872340 (3125 1975);
DISPLAY INVISIBLE (3125 1975);
FORCEPROP 1 LAST PATH I124
J 0
(2798 2100);
DISPLAY 0.872340 (2798 2100);
PAINT GREEN (2798 2100);
DISPLAY INVISIBLE (2798 2100);
FORCEADD TAP..1
(2800 2150);
FORCEPROP 3 LASTPIN (2750 2150) SIG_NAME M_A_CPU0_SB_DQS_DN<2>
J 0
(2760 2160);
DISPLAY 0.659574 (2760 2160);
PAINT MONO (2760 2160);
DISPLAY INVISIBLE (2760 2160);
FORCEPROP 1 LASTPIN (2750 2150) BN 2
J 0
(2738 2158);
DISPLAY 0.680851 (2738 2158);
PAINT GREEN (2738 2158);
FORCEPROP 2 LAST CDS_LIB standard
J 0
(2800 2150);
DISPLAY INVISIBLE (2800 2150);
FORCEPROP 1 LAST BODY_TYPE PLUMBING
J 0
(2800 2200);
DISPLAY 0.872340 (2800 2200);
PAINT GREEN (2800 2200);
DISPLAY INVISIBLE (2800 2200);
FORCEPROP 1 LAST HDL_TAP TRUE
J 0
(3125 2025);
DISPLAY 0.872340 (3125 2025);
DISPLAY INVISIBLE (3125 2025);
FORCEPROP 1 LAST PATH I125
J 0
(2798 2150);
DISPLAY 0.872340 (2798 2150);
PAINT GREEN (2798 2150);
DISPLAY INVISIBLE (2798 2150);
FORCEADD TAP..1
(2800 2050);
FORCEPROP 3 LASTPIN (2750 2050) SIG_NAME M_A_CPU0_SB_DQS_DN<0>
J 0
(2760 2060);
DISPLAY 0.659574 (2760 2060);
PAINT MONO (2760 2060);
DISPLAY INVISIBLE (2760 2060);
FORCEPROP 1 LASTPIN (2750 2050) BN 0
J 0
(2738 2058);
DISPLAY 0.680851 (2738 2058);
PAINT GREEN (2738 2058);
FORCEPROP 2 LAST CDS_LIB standard
J 0
(2800 2050);
DISPLAY INVISIBLE (2800 2050);
FORCEPROP 1 LAST BODY_TYPE PLUMBING
J 0
(2800 2100);
DISPLAY 0.872340 (2800 2100);
PAINT GREEN (2800 2100);
DISPLAY INVISIBLE (2800 2100);
FORCEPROP 1 LAST HDL_TAP TRUE
J 0
(3125 1925);
DISPLAY 0.872340 (3125 1925);
DISPLAY INVISIBLE (3125 1925);
FORCEPROP 1 LAST PATH I126
J 0
(2798 2050);
DISPLAY 0.872340 (2798 2050);
PAINT GREEN (2798 2050);
DISPLAY INVISIBLE (2798 2050);
FORCEADD TAP..1
(2800 1650);
FORCEPROP 3 LASTPIN (2750 1650) SIG_NAME M_A_CPU0_SA_CA<1>
J 0
(2760 1660);
DISPLAY 0.659574 (2760 1660);
PAINT MONO (2760 1660);
DISPLAY INVISIBLE (2760 1660);
FORCEPROP 1 LASTPIN (2750 1650) BN 1
J 0
(2738 1658);
DISPLAY 0.680851 (2738 1658);
PAINT GREEN (2738 1658);
FORCEPROP 2 LAST CDS_LIB standard
J 0
(2800 1650);
DISPLAY INVISIBLE (2800 1650);
FORCEPROP 1 LAST BODY_TYPE PLUMBING
J 0
(2800 1700);
DISPLAY 0.872340 (2800 1700);
PAINT GREEN (2800 1700);
DISPLAY INVISIBLE (2800 1700);
FORCEPROP 1 LAST HDL_TAP TRUE
J 0
(3125 1525);
DISPLAY 0.872340 (3125 1525);
DISPLAY INVISIBLE (3125 1525);
FORCEPROP 1 LAST PATH I127
J 0
(2798 1650);
DISPLAY 0.872340 (2798 1650);
PAINT GREEN (2798 1650);
DISPLAY INVISIBLE (2798 1650);
FORCEADD TAP..1
(2800 1600);
FORCEPROP 3 LASTPIN (2750 1600) SIG_NAME M_A_CPU0_SA_CA<0>
J 0
(2760 1610);
DISPLAY 0.659574 (2760 1610);
PAINT MONO (2760 1610);
DISPLAY INVISIBLE (2760 1610);
FORCEPROP 1 LASTPIN (2750 1600) BN 0
J 0
(2738 1608);
DISPLAY 0.680851 (2738 1608);
PAINT GREEN (2738 1608);
FORCEPROP 2 LAST CDS_LIB standard
J 0
(2800 1600);
DISPLAY INVISIBLE (2800 1600);
FORCEPROP 1 LAST BODY_TYPE PLUMBING
J 0
(2800 1650);
DISPLAY 0.872340 (2800 1650);
PAINT GREEN (2800 1650);
DISPLAY INVISIBLE (2800 1650);
FORCEPROP 1 LAST HDL_TAP TRUE
J 0
(3125 1475);
DISPLAY 0.872340 (3125 1475);
DISPLAY INVISIBLE (3125 1475);
FORCEPROP 1 LAST PATH I128
J 0
(2798 1600);
DISPLAY 0.872340 (2798 1600);
PAINT GREEN (2798 1600);
DISPLAY INVISIBLE (2798 1600);
FORCEADD TAP..1
(2800 1750);
FORCEPROP 3 LASTPIN (2750 1750) SIG_NAME M_A_CPU0_SA_CA<3>
J 0
(2760 1760);
DISPLAY 0.659574 (2760 1760);
PAINT MONO (2760 1760);
DISPLAY INVISIBLE (2760 1760);
FORCEPROP 1 LASTPIN (2750 1750) BN 3
J 0
(2738 1758);
DISPLAY 0.680851 (2738 1758);
PAINT GREEN (2738 1758);
FORCEPROP 2 LAST CDS_LIB standard
J 0
(2800 1750);
DISPLAY INVISIBLE (2800 1750);
FORCEPROP 1 LAST BODY_TYPE PLUMBING
J 0
(2800 1800);
DISPLAY 0.872340 (2800 1800);
PAINT GREEN (2800 1800);
DISPLAY INVISIBLE (2800 1800);
FORCEPROP 1 LAST HDL_TAP TRUE
J 0
(3125 1625);
DISPLAY 0.872340 (3125 1625);
DISPLAY INVISIBLE (3125 1625);
FORCEPROP 1 LAST PATH I129
J 0
(2798 1750);
DISPLAY 0.872340 (2798 1750);
PAINT GREEN (2798 1750);
DISPLAY INVISIBLE (2798 1750);
FORCEADD TAP..1
R 2
(-625 3650);
FORCEPROP 3 LASTPIN (-575 3650) SIG_NAME M_A_CPU0_SA_DQ<20>
J 0
(-565 3660);
DISPLAY 0.659574 (-565 3660);
PAINT MONO (-565 3660);
DISPLAY INVISIBLE (-565 3660);
FORCEPROP 1 LASTPIN (-575 3650) BN 20
J 2
(-563 3658);
DISPLAY 0.680851 (-563 3658);
PAINT GREEN (-563 3658);
FORCEPROP 2 LAST CDS_LIB standard
J 0
(-625 3650);
DISPLAY INVISIBLE (-625 3650);
FORCEPROP 1 LAST BODY_TYPE PLUMBING
J 2
(-625 3700);
DISPLAY 0.872340 (-625 3700);
PAINT GREEN (-625 3700);
DISPLAY INVISIBLE (-625 3700);
FORCEPROP 1 LAST HDL_TAP TRUE
J 2
(-950 3525);
DISPLAY 0.872340 (-950 3525);
DISPLAY INVISIBLE (-950 3525);
FORCEPROP 1 LAST PATH I13
J 2
(-623 3650);
DISPLAY 0.872340 (-623 3650);
PAINT GREEN (-623 3650);
DISPLAY INVISIBLE (-623 3650);
FORCEADD TAP..1
(2800 1700);
FORCEPROP 3 LASTPIN (2750 1700) SIG_NAME M_A_CPU0_SA_CA<2>
J 0
(2760 1710);
DISPLAY 0.659574 (2760 1710);
PAINT MONO (2760 1710);
DISPLAY INVISIBLE (2760 1710);
FORCEPROP 1 LASTPIN (2750 1700) BN 2
J 0
(2738 1708);
DISPLAY 0.680851 (2738 1708);
PAINT GREEN (2738 1708);
FORCEPROP 2 LAST CDS_LIB standard
J 0
(2800 1700);
DISPLAY INVISIBLE (2800 1700);
FORCEPROP 1 LAST BODY_TYPE PLUMBING
J 0
(2800 1750);
DISPLAY 0.872340 (2800 1750);
PAINT GREEN (2800 1750);
DISPLAY INVISIBLE (2800 1750);
FORCEPROP 1 LAST HDL_TAP TRUE
J 0
(3125 1575);
DISPLAY 0.872340 (3125 1575);
DISPLAY INVISIBLE (3125 1575);
FORCEPROP 1 LAST PATH I130
J 0
(2798 1700);
DISPLAY 0.872340 (2798 1700);
PAINT GREEN (2798 1700);
DISPLAY INVISIBLE (2798 1700);
FORCEADD TAP..1
(2800 1850);
FORCEPROP 3 LASTPIN (2750 1850) SIG_NAME M_A_CPU0_SA_CA<5>
J 0
(2760 1860);
DISPLAY 0.659574 (2760 1860);
PAINT MONO (2760 1860);
DISPLAY INVISIBLE (2760 1860);
FORCEPROP 1 LASTPIN (2750 1850) BN 5
J 0
(2738 1858);
DISPLAY 0.680851 (2738 1858);
PAINT GREEN (2738 1858);
FORCEPROP 2 LAST CDS_LIB standard
J 0
(2800 1850);
DISPLAY INVISIBLE (2800 1850);
FORCEPROP 1 LAST BODY_TYPE PLUMBING
J 0
(2800 1900);
DISPLAY 0.872340 (2800 1900);
PAINT GREEN (2800 1900);
DISPLAY INVISIBLE (2800 1900);
FORCEPROP 1 LAST HDL_TAP TRUE
J 0
(3125 1725);
DISPLAY 0.872340 (3125 1725);
DISPLAY INVISIBLE (3125 1725);
FORCEPROP 1 LAST PATH I131
J 0
(2798 1850);
DISPLAY 0.872340 (2798 1850);
PAINT GREEN (2798 1850);
DISPLAY INVISIBLE (2798 1850);
FORCEADD TAP..1
(2800 1900);
FORCEPROP 3 LASTPIN (2750 1900) SIG_NAME M_A_CPU0_SA_CA<6>
J 0
(2760 1910);
DISPLAY 0.659574 (2760 1910);
PAINT MONO (2760 1910);
DISPLAY INVISIBLE (2760 1910);
FORCEPROP 1 LASTPIN (2750 1900) BN 6
J 0
(2738 1908);
DISPLAY 0.680851 (2738 1908);
PAINT GREEN (2738 1908);
FORCEPROP 2 LAST CDS_LIB standard
J 0
(2800 1900);
DISPLAY INVISIBLE (2800 1900);
FORCEPROP 1 LAST BODY_TYPE PLUMBING
J 0
(2800 1950);
DISPLAY 0.872340 (2800 1950);
PAINT GREEN (2800 1950);
DISPLAY INVISIBLE (2800 1950);
FORCEPROP 1 LAST HDL_TAP TRUE
J 0
(3125 1775);
DISPLAY 0.872340 (3125 1775);
DISPLAY INVISIBLE (3125 1775);
FORCEPROP 1 LAST PATH I132
J 0
(2798 1900);
DISPLAY 0.872340 (2798 1900);
PAINT GREEN (2798 1900);
DISPLAY INVISIBLE (2798 1900);
FORCEADD TAP..1
(2800 1800);
FORCEPROP 3 LASTPIN (2750 1800) SIG_NAME M_A_CPU0_SA_CA<4>
J 0
(2760 1810);
DISPLAY 0.659574 (2760 1810);
PAINT MONO (2760 1810);
DISPLAY INVISIBLE (2760 1810);
FORCEPROP 1 LASTPIN (2750 1800) BN 4
J 0
(2738 1808);
DISPLAY 0.680851 (2738 1808);
PAINT GREEN (2738 1808);
FORCEPROP 2 LAST CDS_LIB standard
J 0
(2800 1800);
DISPLAY INVISIBLE (2800 1800);
FORCEPROP 1 LAST BODY_TYPE PLUMBING
J 0
(2800 1850);
DISPLAY 0.872340 (2800 1850);
PAINT GREEN (2800 1850);
DISPLAY INVISIBLE (2800 1850);
FORCEPROP 1 LAST HDL_TAP TRUE
J 0
(3125 1675);
DISPLAY 0.872340 (3125 1675);
DISPLAY INVISIBLE (3125 1675);
FORCEPROP 1 LAST PATH I133
J 0
(2798 1800);
DISPLAY 0.872340 (2798 1800);
PAINT GREEN (2798 1800);
DISPLAY INVISIBLE (2798 1800);
FORCEADD OFFPAGE..3
(3900 1925);
FORCEPROP 2 LAST $XR1 83 
J 0
(4204 1925);
DISPLAY 0.638298 (4204 1925);
PAINT MONO (4204 1925);
FORCEPROP 2 LAST $XR0 82 
J 0
(4114 1925);
DISPLAY 0.638298 (4114 1925);
PAINT MONO (4114 1925);
FORCEPROP 2 LAST CDS_LIB standard
J 2
(3900 1925);
DISPLAY INVISIBLE (3900 1925);
FORCEPROP 1 LAST OFFPAGE TRUE
J 0
(4225 1800);
DISPLAY 0.872340 (4225 1800);
DISPLAY INVISIBLE (4225 1800);
FORCEPROP 1 LAST COMMENT_BODY TRUE
J 0
(3850 1825);
DISPLAY 0.872340 (3850 1825);
PAINT GREEN (3850 1825);
DISPLAY INVISIBLE (3850 1825);
FORCEPROP 2 LAST PATH I134
J 0
(4100 2000);
DISPLAY 1.021277 (4100 2000);
DISPLAY INVISIBLE (4100 2000);
FORCEADD OFFPAGE..2
(3900 1550);
FORCEPROP 2 LAST $XR1 83 
J 0
(4179 1550);
DISPLAY 0.638298 (4179 1550);
PAINT MONO (4179 1550);
FORCEPROP 2 LAST $XR0 82 
J 0
(4089 1550);
DISPLAY 0.638298 (4089 1550);
PAINT MONO (4089 1550);
FORCEPROP 2 LAST CDS_LIB standard
J 0
(3900 1550);
PAINT MONO (3900 1550);
DISPLAY INVISIBLE (3900 1550);
FORCEPROP 1 LAST OFFPAGE TRUE
J 0
(4225 1425);
DISPLAY 1.170213 (4225 1425);
PAINT GREEN (4225 1425);
DISPLAY INVISIBLE (4225 1425);
FORCEPROP 1 LAST COMMENT_BODY TRUE
J 0
(3855 1455);
DISPLAY 1.170213 (3855 1455);
PAINT GREEN (3855 1455);
DISPLAY INVISIBLE (3855 1455);
FORCEPROP 2 LAST PATH I135
J 0
(4075 1625);
DISPLAY 1.021277 (4075 1625);
DISPLAY INVISIBLE (4075 1625);
FORCEADD OFFPAGE..3
(3900 1425);
FORCEPROP 2 LAST $XR1 83 
J 0
(4204 1425);
DISPLAY 0.638298 (4204 1425);
PAINT MONO (4204 1425);
FORCEPROP 2 LAST $XR0 82 
J 0
(4114 1425);
DISPLAY 0.638298 (4114 1425);
PAINT MONO (4114 1425);
FORCEPROP 2 LAST CDS_LIB standard
J 2
(3900 1425);
DISPLAY INVISIBLE (3900 1425);
FORCEPROP 1 LAST OFFPAGE TRUE
J 0
(4225 1300);
DISPLAY 0.872340 (4225 1300);
DISPLAY INVISIBLE (4225 1300);
FORCEPROP 1 LAST COMMENT_BODY TRUE
J 0
(3850 1325);
DISPLAY 0.872340 (3850 1325);
PAINT GREEN (3850 1325);
DISPLAY INVISIBLE (3850 1325);
FORCEPROP 2 LAST PATH I136
J 0
(4100 1500);
DISPLAY 1.021277 (4100 1500);
DISPLAY INVISIBLE (4100 1500);
FORCEADD OFFPAGE..2
(3900 1050);
FORCEPROP 2 LAST $XR1 83 
J 0
(4179 1050);
DISPLAY 0.638298 (4179 1050);
PAINT MONO (4179 1050);
FORCEPROP 2 LAST $XR0 82 
J 0
(4089 1050);
DISPLAY 0.638298 (4089 1050);
PAINT MONO (4089 1050);
FORCEPROP 2 LAST CDS_LIB standard
J 0
(3900 1050);
PAINT MONO (3900 1050);
DISPLAY INVISIBLE (3900 1050);
FORCEPROP 1 LAST OFFPAGE TRUE
J 0
(4225 925);
DISPLAY 1.170213 (4225 925);
PAINT GREEN (4225 925);
DISPLAY INVISIBLE (4225 925);
FORCEPROP 1 LAST COMMENT_BODY TRUE
J 0
(3855 955);
DISPLAY 1.170213 (3855 955);
PAINT GREEN (3855 955);
DISPLAY INVISIBLE (3855 955);
FORCEPROP 2 LAST PATH I137
J 0
(4075 1125);
DISPLAY 1.021277 (4075 1125);
DISPLAY INVISIBLE (4075 1125);
FORCEADD TAP..1
(2800 1350);
FORCEPROP 3 LASTPIN (2750 1350) SIG_NAME M_A_CPU0_SB_CA<5>
J 0
(2760 1360);
DISPLAY 0.659574 (2760 1360);
PAINT MONO (2760 1360);
DISPLAY INVISIBLE (2760 1360);
FORCEPROP 1 LASTPIN (2750 1350) BN 5
J 0
(2738 1358);
DISPLAY 0.680851 (2738 1358);
PAINT GREEN (2738 1358);
FORCEPROP 2 LAST CDS_LIB standard
J 0
(2800 1350);
DISPLAY INVISIBLE (2800 1350);
FORCEPROP 1 LAST BODY_TYPE PLUMBING
J 0
(2800 1400);
DISPLAY 0.872340 (2800 1400);
PAINT GREEN (2800 1400);
DISPLAY INVISIBLE (2800 1400);
FORCEPROP 1 LAST HDL_TAP TRUE
J 0
(3125 1225);
DISPLAY 0.872340 (3125 1225);
DISPLAY INVISIBLE (3125 1225);
FORCEPROP 1 LAST PATH I138
J 0
(2798 1350);
DISPLAY 0.872340 (2798 1350);
PAINT GREEN (2798 1350);
DISPLAY INVISIBLE (2798 1350);
FORCEADD TAP..1
(2800 1400);
FORCEPROP 3 LASTPIN (2750 1400) SIG_NAME M_A_CPU0_SB_CA<6>
J 0
(2760 1410);
DISPLAY 0.659574 (2760 1410);
PAINT MONO (2760 1410);
DISPLAY INVISIBLE (2760 1410);
FORCEPROP 1 LASTPIN (2750 1400) BN 6
J 0
(2738 1408);
DISPLAY 0.680851 (2738 1408);
PAINT GREEN (2738 1408);
FORCEPROP 2 LAST CDS_LIB standard
J 0
(2800 1400);
DISPLAY INVISIBLE (2800 1400);
FORCEPROP 1 LAST BODY_TYPE PLUMBING
J 0
(2800 1450);
DISPLAY 0.872340 (2800 1450);
PAINT GREEN (2800 1450);
DISPLAY INVISIBLE (2800 1450);
FORCEPROP 1 LAST HDL_TAP TRUE
J 0
(3125 1275);
DISPLAY 0.872340 (3125 1275);
DISPLAY INVISIBLE (3125 1275);
FORCEPROP 1 LAST PATH I139
J 0
(2798 1400);
DISPLAY 0.872340 (2798 1400);
PAINT GREEN (2798 1400);
DISPLAY INVISIBLE (2798 1400);
FORCEADD TAP..1
R 2
(-625 3700);
FORCEPROP 3 LASTPIN (-575 3700) SIG_NAME M_A_CPU0_SA_DQ<21>
J 0
(-565 3710);
DISPLAY 0.659574 (-565 3710);
PAINT MONO (-565 3710);
DISPLAY INVISIBLE (-565 3710);
FORCEPROP 1 LASTPIN (-575 3700) BN 21
J 2
(-563 3708);
DISPLAY 0.680851 (-563 3708);
PAINT GREEN (-563 3708);
FORCEPROP 2 LAST CDS_LIB standard
J 0
(-625 3700);
DISPLAY INVISIBLE (-625 3700);
FORCEPROP 1 LAST BODY_TYPE PLUMBING
J 2
(-625 3750);
DISPLAY 0.872340 (-625 3750);
PAINT GREEN (-625 3750);
DISPLAY INVISIBLE (-625 3750);
FORCEPROP 1 LAST HDL_TAP TRUE
J 2
(-950 3575);
DISPLAY 0.872340 (-950 3575);
DISPLAY INVISIBLE (-950 3575);
FORCEPROP 1 LAST PATH I14
J 2
(-623 3700);
DISPLAY 0.872340 (-623 3700);
PAINT GREEN (-623 3700);
DISPLAY INVISIBLE (-623 3700);
FORCEADD TAP..1
(2800 1300);
FORCEPROP 3 LASTPIN (2750 1300) SIG_NAME M_A_CPU0_SB_CA<4>
J 0
(2760 1310);
DISPLAY 0.659574 (2760 1310);
PAINT MONO (2760 1310);
DISPLAY INVISIBLE (2760 1310);
FORCEPROP 1 LASTPIN (2750 1300) BN 4
J 0
(2738 1308);
DISPLAY 0.680851 (2738 1308);
PAINT GREEN (2738 1308);
FORCEPROP 2 LAST CDS_LIB standard
J 0
(2800 1300);
DISPLAY INVISIBLE (2800 1300);
FORCEPROP 1 LAST BODY_TYPE PLUMBING
J 0
(2800 1350);
DISPLAY 0.872340 (2800 1350);
PAINT GREEN (2800 1350);
DISPLAY INVISIBLE (2800 1350);
FORCEPROP 1 LAST HDL_TAP TRUE
J 0
(3125 1175);
DISPLAY 0.872340 (3125 1175);
DISPLAY INVISIBLE (3125 1175);
FORCEPROP 1 LAST PATH I140
J 0
(2798 1300);
DISPLAY 0.872340 (2798 1300);
PAINT GREEN (2798 1300);
DISPLAY INVISIBLE (2798 1300);
FORCEADD TAP..1
(2800 1250);
FORCEPROP 3 LASTPIN (2750 1250) SIG_NAME M_A_CPU0_SB_CA<3>
J 0
(2760 1260);
DISPLAY 0.659574 (2760 1260);
PAINT MONO (2760 1260);
DISPLAY INVISIBLE (2760 1260);
FORCEPROP 1 LASTPIN (2750 1250) BN 3
J 0
(2738 1258);
DISPLAY 0.680851 (2738 1258);
PAINT GREEN (2738 1258);
FORCEPROP 2 LAST CDS_LIB standard
J 0
(2800 1250);
DISPLAY INVISIBLE (2800 1250);
FORCEPROP 1 LAST BODY_TYPE PLUMBING
J 0
(2800 1300);
DISPLAY 0.872340 (2800 1300);
PAINT GREEN (2800 1300);
DISPLAY INVISIBLE (2800 1300);
FORCEPROP 1 LAST HDL_TAP TRUE
J 0
(3125 1125);
DISPLAY 0.872340 (3125 1125);
DISPLAY INVISIBLE (3125 1125);
FORCEPROP 1 LAST PATH I141
J 0
(2798 1250);
DISPLAY 0.872340 (2798 1250);
PAINT GREEN (2798 1250);
DISPLAY INVISIBLE (2798 1250);
FORCEADD TAP..1
(2800 1200);
FORCEPROP 3 LASTPIN (2750 1200) SIG_NAME M_A_CPU0_SB_CA<2>
J 0
(2760 1210);
DISPLAY 0.659574 (2760 1210);
PAINT MONO (2760 1210);
DISPLAY INVISIBLE (2760 1210);
FORCEPROP 1 LASTPIN (2750 1200) BN 2
J 0
(2738 1208);
DISPLAY 0.680851 (2738 1208);
PAINT GREEN (2738 1208);
FORCEPROP 2 LAST CDS_LIB standard
J 0
(2800 1200);
DISPLAY INVISIBLE (2800 1200);
FORCEPROP 1 LAST BODY_TYPE PLUMBING
J 0
(2800 1250);
DISPLAY 0.872340 (2800 1250);
PAINT GREEN (2800 1250);
DISPLAY INVISIBLE (2800 1250);
FORCEPROP 1 LAST HDL_TAP TRUE
J 0
(3125 1075);
DISPLAY 0.872340 (3125 1075);
DISPLAY INVISIBLE (3125 1075);
FORCEPROP 1 LAST PATH I142
J 0
(2798 1200);
DISPLAY 0.872340 (2798 1200);
PAINT GREEN (2798 1200);
DISPLAY INVISIBLE (2798 1200);
FORCEADD TAP..1
(2800 1150);
FORCEPROP 3 LASTPIN (2750 1150) SIG_NAME M_A_CPU0_SB_CA<1>
J 0
(2760 1160);
DISPLAY 0.659574 (2760 1160);
PAINT MONO (2760 1160);
DISPLAY INVISIBLE (2760 1160);
FORCEPROP 1 LASTPIN (2750 1150) BN 1
J 0
(2738 1158);
DISPLAY 0.680851 (2738 1158);
PAINT GREEN (2738 1158);
FORCEPROP 2 LAST CDS_LIB standard
J 0
(2800 1150);
DISPLAY INVISIBLE (2800 1150);
FORCEPROP 1 LAST BODY_TYPE PLUMBING
J 0
(2800 1200);
DISPLAY 0.872340 (2800 1200);
PAINT GREEN (2800 1200);
DISPLAY INVISIBLE (2800 1200);
FORCEPROP 1 LAST HDL_TAP TRUE
J 0
(3125 1025);
DISPLAY 0.872340 (3125 1025);
DISPLAY INVISIBLE (3125 1025);
FORCEPROP 1 LAST PATH I143
J 0
(2798 1150);
DISPLAY 0.872340 (2798 1150);
PAINT GREEN (2798 1150);
DISPLAY INVISIBLE (2798 1150);
FORCEADD TAP..1
(2800 1100);
FORCEPROP 3 LASTPIN (2750 1100) SIG_NAME M_A_CPU0_SB_CA<0>
J 0
(2760 1110);
DISPLAY 0.659574 (2760 1110);
PAINT MONO (2760 1110);
DISPLAY INVISIBLE (2760 1110);
FORCEPROP 1 LASTPIN (2750 1100) BN 0
J 0
(2738 1108);
DISPLAY 0.680851 (2738 1108);
PAINT GREEN (2738 1108);
FORCEPROP 2 LAST CDS_LIB standard
J 0
(2800 1100);
DISPLAY INVISIBLE (2800 1100);
FORCEPROP 1 LAST BODY_TYPE PLUMBING
J 0
(2800 1150);
DISPLAY 0.872340 (2800 1150);
PAINT GREEN (2800 1150);
DISPLAY INVISIBLE (2800 1150);
FORCEPROP 1 LAST HDL_TAP TRUE
J 0
(3125 975);
DISPLAY 0.872340 (3125 975);
DISPLAY INVISIBLE (3125 975);
FORCEPROP 1 LAST PATH I144
J 0
(2798 1100);
DISPLAY 0.872340 (2798 1100);
PAINT GREEN (2798 1100);
DISPLAY INVISIBLE (2798 1100);
FORCEADD TAP..1
(2800 800);
FORCEPROP 3 LASTPIN (2750 800) SIG_NAME M_A_CPU0_SA_CS_N<1>
J 0
(2760 810);
DISPLAY 0.659574 (2760 810);
PAINT MONO (2760 810);
DISPLAY INVISIBLE (2760 810);
FORCEPROP 1 LASTPIN (2750 800) BN 1
J 0
(2738 808);
DISPLAY 0.680851 (2738 808);
PAINT GREEN (2738 808);
FORCEPROP 2 LAST CDS_LIB standard
J 0
(2800 800);
DISPLAY INVISIBLE (2800 800);
FORCEPROP 1 LAST BODY_TYPE PLUMBING
J 0
(2800 850);
DISPLAY 0.872340 (2800 850);
PAINT GREEN (2800 850);
DISPLAY INVISIBLE (2800 850);
FORCEPROP 1 LAST HDL_TAP TRUE
J 0
(3125 675);
DISPLAY 0.872340 (3125 675);
DISPLAY INVISIBLE (3125 675);
FORCEPROP 1 LAST PATH I147
J 0
(2798 800);
DISPLAY 0.872340 (2798 800);
PAINT GREEN (2798 800);
DISPLAY INVISIBLE (2798 800);
FORCEADD TAP..1
(2800 850);
FORCEPROP 3 LASTPIN (2750 850) SIG_NAME M_A_CPU0_SA_CS_N<2>
J 0
(2760 860);
DISPLAY 0.659574 (2760 860);
PAINT MONO (2760 860);
DISPLAY INVISIBLE (2760 860);
FORCEPROP 1 LASTPIN (2750 850) BN 2
J 0
(2738 858);
DISPLAY 0.680851 (2738 858);
PAINT GREEN (2738 858);
FORCEPROP 2 LAST CDS_LIB standard
J 0
(2800 850);
DISPLAY INVISIBLE (2800 850);
FORCEPROP 1 LAST BODY_TYPE PLUMBING
J 0
(2800 900);
DISPLAY 0.872340 (2800 900);
PAINT GREEN (2800 900);
DISPLAY INVISIBLE (2800 900);
FORCEPROP 1 LAST HDL_TAP TRUE
J 0
(3125 725);
DISPLAY 0.872340 (3125 725);
DISPLAY INVISIBLE (3125 725);
FORCEPROP 1 LAST PATH I148
J 0
(2798 850);
DISPLAY 0.872340 (2798 850);
PAINT GREEN (2798 850);
DISPLAY INVISIBLE (2798 850);
FORCEADD TAP..1
(2800 900);
FORCEPROP 3 LASTPIN (2750 900) SIG_NAME M_A_CPU0_SA_CS_N<3>
J 0
(2760 910);
DISPLAY 0.659574 (2760 910);
PAINT MONO (2760 910);
DISPLAY INVISIBLE (2760 910);
FORCEPROP 1 LASTPIN (2750 900) BN 3
J 0
(2738 908);
DISPLAY 0.680851 (2738 908);
PAINT GREEN (2738 908);
FORCEPROP 2 LAST CDS_LIB standard
J 0
(2800 900);
DISPLAY INVISIBLE (2800 900);
FORCEPROP 1 LAST BODY_TYPE PLUMBING
J 0
(2800 950);
DISPLAY 0.872340 (2800 950);
PAINT GREEN (2800 950);
DISPLAY INVISIBLE (2800 950);
FORCEPROP 1 LAST HDL_TAP TRUE
J 0
(3125 775);
DISPLAY 0.872340 (3125 775);
DISPLAY INVISIBLE (3125 775);
FORCEPROP 1 LAST PATH I149
J 0
(2798 900);
DISPLAY 0.872340 (2798 900);
PAINT GREEN (2798 900);
DISPLAY INVISIBLE (2798 900);
FORCEADD TAP..1
R 2
(-625 3750);
FORCEPROP 3 LASTPIN (-575 3750) SIG_NAME M_A_CPU0_SA_DQ<22>
J 0
(-565 3760);
DISPLAY 0.659574 (-565 3760);
PAINT MONO (-565 3760);
DISPLAY INVISIBLE (-565 3760);
FORCEPROP 1 LASTPIN (-575 3750) BN 22
J 2
(-563 3758);
DISPLAY 0.680851 (-563 3758);
PAINT GREEN (-563 3758);
FORCEPROP 2 LAST CDS_LIB standard
J 0
(-625 3750);
DISPLAY INVISIBLE (-625 3750);
FORCEPROP 1 LAST BODY_TYPE PLUMBING
J 2
(-625 3800);
DISPLAY 0.872340 (-625 3800);
PAINT GREEN (-625 3800);
DISPLAY INVISIBLE (-625 3800);
FORCEPROP 1 LAST HDL_TAP TRUE
J 2
(-950 3625);
DISPLAY 0.872340 (-950 3625);
DISPLAY INVISIBLE (-950 3625);
FORCEPROP 1 LAST PATH I15
J 2
(-623 3750);
DISPLAY 0.872340 (-623 3750);
PAINT GREEN (-623 3750);
DISPLAY INVISIBLE (-623 3750);
FORCEADD TAP..1
(2800 750);
FORCEPROP 3 LASTPIN (2750 750) SIG_NAME M_A_CPU0_SA_CS_N<0>
J 0
(2760 760);
DISPLAY 0.659574 (2760 760);
PAINT MONO (2760 760);
DISPLAY INVISIBLE (2760 760);
FORCEPROP 1 LASTPIN (2750 750) BN 0
J 0
(2738 758);
DISPLAY 0.680851 (2738 758);
PAINT GREEN (2738 758);
FORCEPROP 2 LAST CDS_LIB standard
J 0
(2800 750);
DISPLAY INVISIBLE (2800 750);
FORCEPROP 1 LAST BODY_TYPE PLUMBING
J 0
(2800 800);
DISPLAY 0.872340 (2800 800);
PAINT GREEN (2800 800);
DISPLAY INVISIBLE (2800 800);
FORCEPROP 1 LAST HDL_TAP TRUE
J 0
(3125 625);
DISPLAY 0.872340 (3125 625);
DISPLAY INVISIBLE (3125 625);
FORCEPROP 1 LAST PATH I150
J 0
(2798 750);
DISPLAY 0.872340 (2798 750);
PAINT GREEN (2798 750);
DISPLAY INVISIBLE (2798 750);
FORCEADD OFFPAGE..2
(3900 925);
FORCEPROP 2 LAST $XR1 83 
J 0
(4179 925);
DISPLAY 0.638298 (4179 925);
PAINT MONO (4179 925);
FORCEPROP 2 LAST $XR0 82 
J 0
(4089 925);
DISPLAY 0.638298 (4089 925);
PAINT MONO (4089 925);
FORCEPROP 2 LAST CDS_LIB standard
J 0
(3900 925);
PAINT MONO (3900 925);
DISPLAY INVISIBLE (3900 925);
FORCEPROP 1 LAST OFFPAGE TRUE
J 0
(4225 800);
DISPLAY 1.170213 (4225 800);
PAINT GREEN (4225 800);
DISPLAY INVISIBLE (4225 800);
FORCEPROP 1 LAST COMMENT_BODY TRUE
J 0
(3855 830);
DISPLAY 1.170213 (3855 830);
PAINT GREEN (3855 830);
DISPLAY INVISIBLE (3855 830);
FORCEPROP 2 LAST PATH I151
J 0
(4075 1000);
DISPLAY 1.021277 (4075 1000);
DISPLAY INVISIBLE (4075 1000);
FORCEADD OFFPAGE..2
(3900 625);
FORCEPROP 2 LAST $XR1 83 
J 0
(4179 625);
DISPLAY 0.638298 (4179 625);
PAINT MONO (4179 625);
FORCEPROP 2 LAST $XR0 82 
J 0
(4089 625);
DISPLAY 0.638298 (4089 625);
PAINT MONO (4089 625);
FORCEPROP 2 LAST CDS_LIB standard
J 0
(3900 625);
PAINT MONO (3900 625);
DISPLAY INVISIBLE (3900 625);
FORCEPROP 1 LAST OFFPAGE TRUE
J 0
(4225 500);
DISPLAY 1.170213 (4225 500);
PAINT GREEN (4225 500);
DISPLAY INVISIBLE (4225 500);
FORCEPROP 1 LAST COMMENT_BODY TRUE
J 0
(3855 530);
DISPLAY 1.170213 (3855 530);
PAINT GREEN (3855 530);
DISPLAY INVISIBLE (3855 530);
FORCEPROP 2 LAST PATH I152
J 0
(4075 700);
DISPLAY 1.021277 (4075 700);
DISPLAY INVISIBLE (4075 700);
FORCEADD TAP..1
(2800 600);
FORCEPROP 3 LASTPIN (2750 600) SIG_NAME M_A_CPU0_SB_CS_N<3>
J 0
(2760 610);
DISPLAY 0.659574 (2760 610);
PAINT MONO (2760 610);
DISPLAY INVISIBLE (2760 610);
FORCEPROP 1 LASTPIN (2750 600) BN 3
J 0
(2738 608);
DISPLAY 0.680851 (2738 608);
PAINT GREEN (2738 608);
FORCEPROP 2 LAST CDS_LIB standard
J 0
(2800 600);
DISPLAY INVISIBLE (2800 600);
FORCEPROP 1 LAST BODY_TYPE PLUMBING
J 0
(2800 650);
DISPLAY 0.872340 (2800 650);
PAINT GREEN (2800 650);
DISPLAY INVISIBLE (2800 650);
FORCEPROP 1 LAST HDL_TAP TRUE
J 0
(3125 475);
DISPLAY 0.872340 (3125 475);
DISPLAY INVISIBLE (3125 475);
FORCEPROP 1 LAST PATH I153
J 0
(2798 600);
DISPLAY 0.872340 (2798 600);
PAINT GREEN (2798 600);
DISPLAY INVISIBLE (2798 600);
FORCEADD TAP..1
(2800 500);
FORCEPROP 3 LASTPIN (2750 500) SIG_NAME M_A_CPU0_SB_CS_N<1>
J 0
(2760 510);
DISPLAY 0.659574 (2760 510);
PAINT MONO (2760 510);
DISPLAY INVISIBLE (2760 510);
FORCEPROP 1 LASTPIN (2750 500) BN 1
J 0
(2738 508);
DISPLAY 0.680851 (2738 508);
PAINT GREEN (2738 508);
FORCEPROP 2 LAST CDS_LIB standard
J 0
(2800 500);
DISPLAY INVISIBLE (2800 500);
FORCEPROP 1 LAST BODY_TYPE PLUMBING
J 0
(2800 550);
DISPLAY 0.872340 (2800 550);
PAINT GREEN (2800 550);
DISPLAY INVISIBLE (2800 550);
FORCEPROP 1 LAST HDL_TAP TRUE
J 0
(3125 375);
DISPLAY 0.872340 (3125 375);
DISPLAY INVISIBLE (3125 375);
FORCEPROP 1 LAST PATH I154
J 0
(2798 500);
DISPLAY 0.872340 (2798 500);
PAINT GREEN (2798 500);
DISPLAY INVISIBLE (2798 500);
FORCEADD TAP..1
(2800 550);
FORCEPROP 3 LASTPIN (2750 550) SIG_NAME M_A_CPU0_SB_CS_N<2>
J 0
(2760 560);
DISPLAY 0.659574 (2760 560);
PAINT MONO (2760 560);
DISPLAY INVISIBLE (2760 560);
FORCEPROP 1 LASTPIN (2750 550) BN 2
J 0
(2738 558);
DISPLAY 0.680851 (2738 558);
PAINT GREEN (2738 558);
FORCEPROP 2 LAST CDS_LIB standard
J 0
(2800 550);
DISPLAY INVISIBLE (2800 550);
FORCEPROP 1 LAST BODY_TYPE PLUMBING
J 0
(2800 600);
DISPLAY 0.872340 (2800 600);
PAINT GREEN (2800 600);
DISPLAY INVISIBLE (2800 600);
FORCEPROP 1 LAST HDL_TAP TRUE
J 0
(3125 425);
DISPLAY 0.872340 (3125 425);
DISPLAY INVISIBLE (3125 425);
FORCEPROP 1 LAST PATH I155
J 0
(2798 550);
DISPLAY 0.872340 (2798 550);
PAINT GREEN (2798 550);
DISPLAY INVISIBLE (2798 550);
FORCEADD TAP..1
(2800 450);
FORCEPROP 3 LASTPIN (2750 450) SIG_NAME M_A_CPU0_SB_CS_N<0>
J 0
(2760 460);
DISPLAY 0.659574 (2760 460);
PAINT MONO (2760 460);
DISPLAY INVISIBLE (2760 460);
FORCEPROP 1 LASTPIN (2750 450) BN 0
J 0
(2738 458);
DISPLAY 0.680851 (2738 458);
PAINT GREEN (2738 458);
FORCEPROP 2 LAST CDS_LIB standard
J 0
(2800 450);
DISPLAY INVISIBLE (2800 450);
FORCEPROP 1 LAST BODY_TYPE PLUMBING
J 0
(2800 500);
DISPLAY 0.872340 (2800 500);
PAINT GREEN (2800 500);
DISPLAY INVISIBLE (2800 500);
FORCEPROP 1 LAST HDL_TAP TRUE
J 0
(3125 325);
DISPLAY 0.872340 (3125 325);
DISPLAY INVISIBLE (3125 325);
FORCEPROP 1 LAST PATH I156
J 0
(2798 450);
DISPLAY 0.872340 (2798 450);
PAINT GREEN (2798 450);
DISPLAY INVISIBLE (2798 450);
FORCEADD OFFPAGE..4
(3900 300);
FORCEPROP 2 LAST $XR0 83 
J 0
(4086 300);
DISPLAY 0.638298 (4086 300);
PAINT MONO (4086 300);
FORCEPROP 2 LAST CDS_LIB standard
J 0
(3900 300);
PAINT MONO (3900 300);
DISPLAY INVISIBLE (3900 300);
FORCEPROP 1 LAST OFFPAGE TRUE
J 0
(4225 175);
DISPLAY 1.170213 (4225 175);
PAINT GREEN (4225 175);
DISPLAY INVISIBLE (4225 175);
FORCEPROP 1 LAST COMMENT_BODY TRUE
J 0
(3875 200);
DISPLAY 1.170213 (3875 200);
PAINT GREEN (3875 200);
DISPLAY INVISIBLE (3875 200);
FORCEPROP 2 LAST PATH I157
J 0
(4075 375);
DISPLAY 1.021277 (4075 375);
DISPLAY INVISIBLE (4075 375);
FORCEADD OFFPAGE..4
(3900 250);
FORCEPROP 2 LAST $XR0 82 
J 0
(4086 250);
DISPLAY 0.638298 (4086 250);
PAINT MONO (4086 250);
FORCEPROP 2 LAST CDS_LIB standard
J 0
(3900 250);
PAINT MONO (3900 250);
DISPLAY INVISIBLE (3900 250);
FORCEPROP 1 LAST OFFPAGE TRUE
J 0
(4225 125);
DISPLAY 1.170213 (4225 125);
PAINT GREEN (4225 125);
DISPLAY INVISIBLE (4225 125);
FORCEPROP 1 LAST COMMENT_BODY TRUE
J 0
(3875 150);
DISPLAY 1.170213 (3875 150);
PAINT GREEN (3875 150);
DISPLAY INVISIBLE (3875 150);
FORCEPROP 2 LAST PATH I158
J 0
(4075 325);
DISPLAY 1.021277 (4075 325);
DISPLAY INVISIBLE (4075 325);
FORCEADD OFFPAGE..4
(3900 150);
FORCEPROP 2 LAST $XR0 83 
J 0
(4086 150);
DISPLAY 0.638298 (4086 150);
PAINT MONO (4086 150);
FORCEPROP 2 LAST CDS_LIB standard
J 0
(3900 150);
PAINT MONO (3900 150);
DISPLAY INVISIBLE (3900 150);
FORCEPROP 1 LAST OFFPAGE TRUE
J 0
(4225 25);
DISPLAY 1.170213 (4225 25);
PAINT GREEN (4225 25);
DISPLAY INVISIBLE (4225 25);
FORCEPROP 1 LAST COMMENT_BODY TRUE
J 0
(3875 50);
DISPLAY 1.170213 (3875 50);
PAINT GREEN (3875 50);
DISPLAY INVISIBLE (3875 50);
FORCEPROP 2 LAST PATH I159
J 0
(4075 225);
DISPLAY 1.021277 (4075 225);
DISPLAY INVISIBLE (4075 225);
FORCEADD TAP..1
R 2
(-625 3850);
FORCEPROP 3 LASTPIN (-575 3850) SIG_NAME M_A_CPU0_SA_DQ<24>
J 0
(-565 3860);
DISPLAY 0.659574 (-565 3860);
PAINT MONO (-565 3860);
DISPLAY INVISIBLE (-565 3860);
FORCEPROP 1 LASTPIN (-575 3850) BN 24
J 2
(-563 3858);
DISPLAY 0.680851 (-563 3858);
PAINT GREEN (-563 3858);
FORCEPROP 2 LAST CDS_LIB standard
J 0
(-625 3850);
DISPLAY INVISIBLE (-625 3850);
FORCEPROP 1 LAST BODY_TYPE PLUMBING
J 2
(-625 3900);
DISPLAY 0.872340 (-625 3900);
PAINT GREEN (-625 3900);
DISPLAY INVISIBLE (-625 3900);
FORCEPROP 1 LAST HDL_TAP TRUE
J 2
(-950 3725);
DISPLAY 0.872340 (-950 3725);
DISPLAY INVISIBLE (-950 3725);
FORCEPROP 1 LAST PATH I16
J 2
(-623 3850);
DISPLAY 0.872340 (-623 3850);
PAINT GREEN (-623 3850);
DISPLAY INVISIBLE (-623 3850);
FORCEADD OFFPAGE..4
(3900 100);
FORCEPROP 2 LAST $XR0 82 
J 0
(4086 100);
DISPLAY 0.638298 (4086 100);
PAINT MONO (4086 100);
FORCEPROP 2 LAST CDS_LIB standard
J 0
(3900 100);
PAINT MONO (3900 100);
DISPLAY INVISIBLE (3900 100);
FORCEPROP 1 LAST OFFPAGE TRUE
J 0
(4225 -25);
DISPLAY 1.170213 (4225 -25);
PAINT GREEN (4225 -25);
DISPLAY INVISIBLE (4225 -25);
FORCEPROP 1 LAST COMMENT_BODY TRUE
J 0
(3875 0);
DISPLAY 1.170213 (3875 0);
PAINT GREEN (3875 0);
DISPLAY INVISIBLE (3875 0);
FORCEPROP 2 LAST PATH I160
J 0
(4075 175);
DISPLAY 1.021277 (4075 175);
DISPLAY INVISIBLE (4075 175);
FORCEADD OFFPAGE..4
(3900 0);
FORCEPROP 2 LAST $XR1 83 
J 0
(4176 0);
DISPLAY 0.638298 (4176 0);
PAINT MONO (4176 0);
FORCEPROP 2 LAST $XR0 82 
J 0
(4086 0);
DISPLAY 0.638298 (4086 0);
PAINT MONO (4086 0);
FORCEPROP 2 LAST CDS_LIB standard
J 0
(3900 0);
PAINT MONO (3900 0);
DISPLAY INVISIBLE (3900 0);
FORCEPROP 1 LAST OFFPAGE TRUE
J 0
(4225 -125);
DISPLAY 1.170213 (4225 -125);
PAINT GREEN (4225 -125);
DISPLAY INVISIBLE (4225 -125);
FORCEPROP 1 LAST COMMENT_BODY TRUE
J 0
(3875 -100);
DISPLAY 1.170213 (3875 -100);
PAINT GREEN (3875 -100);
DISPLAY INVISIBLE (3875 -100);
FORCEPROP 2 LAST PATH I161
J 0
(4075 75);
DISPLAY 1.021277 (4075 75);
DISPLAY INVISIBLE (4075 75);
FORCEADD TAP..1
R 2
(-625 500);
FORCEPROP 3 LASTPIN (-575 500) SIG_NAME M_A_CPU0_SB_CB<5>
J 0
(-565 510);
DISPLAY 0.659574 (-565 510);
PAINT MONO (-565 510);
DISPLAY INVISIBLE (-565 510);
FORCEPROP 1 LASTPIN (-575 500) BN 5
J 2
(-563 508);
DISPLAY 0.680851 (-563 508);
PAINT GREEN (-563 508);
FORCEPROP 2 LAST CDS_LIB standard
J 0
(-625 500);
DISPLAY INVISIBLE (-625 500);
FORCEPROP 1 LAST BODY_TYPE PLUMBING
J 2
(-625 550);
DISPLAY 0.872340 (-625 550);
PAINT GREEN (-625 550);
DISPLAY INVISIBLE (-625 550);
FORCEPROP 1 LAST HDL_TAP TRUE
J 2
(-950 375);
DISPLAY 0.872340 (-950 375);
DISPLAY INVISIBLE (-950 375);
FORCEPROP 1 LAST PATH I162
J 2
(-623 500);
DISPLAY 0.872340 (-623 500);
PAINT GREEN (-623 500);
DISPLAY INVISIBLE (-623 500);
FORCEADD TAP..1
R 2
(-625 550);
FORCEPROP 3 LASTPIN (-575 550) SIG_NAME M_A_CPU0_SB_CB<6>
J 0
(-565 560);
DISPLAY 0.659574 (-565 560);
PAINT MONO (-565 560);
DISPLAY INVISIBLE (-565 560);
FORCEPROP 1 LASTPIN (-575 550) BN 6
J 2
(-563 558);
DISPLAY 0.680851 (-563 558);
PAINT GREEN (-563 558);
FORCEPROP 2 LAST CDS_LIB standard
J 0
(-625 550);
DISPLAY INVISIBLE (-625 550);
FORCEPROP 1 LAST BODY_TYPE PLUMBING
J 2
(-625 600);
DISPLAY 0.872340 (-625 600);
PAINT GREEN (-625 600);
DISPLAY INVISIBLE (-625 600);
FORCEPROP 1 LAST HDL_TAP TRUE
J 2
(-950 425);
DISPLAY 0.872340 (-950 425);
DISPLAY INVISIBLE (-950 425);
FORCEPROP 1 LAST PATH I163
J 2
(-623 550);
DISPLAY 0.872340 (-623 550);
PAINT GREEN (-623 550);
DISPLAY INVISIBLE (-623 550);
FORCEADD TAP..1
R 2
(-625 600);
FORCEPROP 3 LASTPIN (-575 600) SIG_NAME M_A_CPU0_SB_CB<7>
J 0
(-565 610);
DISPLAY 0.659574 (-565 610);
PAINT MONO (-565 610);
DISPLAY INVISIBLE (-565 610);
FORCEPROP 1 LASTPIN (-575 600) BN 7
J 2
(-563 608);
DISPLAY 0.680851 (-563 608);
PAINT GREEN (-563 608);
FORCEPROP 2 LAST CDS_LIB standard
J 0
(-625 600);
DISPLAY INVISIBLE (-625 600);
FORCEPROP 1 LAST BODY_TYPE PLUMBING
J 2
(-625 650);
DISPLAY 0.872340 (-625 650);
PAINT GREEN (-625 650);
DISPLAY INVISIBLE (-625 650);
FORCEPROP 1 LAST HDL_TAP TRUE
J 2
(-950 475);
DISPLAY 0.872340 (-950 475);
DISPLAY INVISIBLE (-950 475);
FORCEPROP 1 LAST PATH I164
J 2
(-623 600);
DISPLAY 0.872340 (-623 600);
PAINT GREEN (-623 600);
DISPLAY INVISIBLE (-623 600);
FORCEADD TAP..1
R 2
(-625 450);
FORCEPROP 3 LASTPIN (-575 450) SIG_NAME M_A_CPU0_SB_CB<4>
J 0
(-565 460);
DISPLAY 0.659574 (-565 460);
PAINT MONO (-565 460);
DISPLAY INVISIBLE (-565 460);
FORCEPROP 1 LASTPIN (-575 450) BN 4
J 2
(-563 458);
DISPLAY 0.680851 (-563 458);
PAINT GREEN (-563 458);
FORCEPROP 2 LAST CDS_LIB standard
J 0
(-625 450);
DISPLAY INVISIBLE (-625 450);
FORCEPROP 1 LAST BODY_TYPE PLUMBING
J 2
(-625 500);
DISPLAY 0.872340 (-625 500);
PAINT GREEN (-625 500);
DISPLAY INVISIBLE (-625 500);
FORCEPROP 1 LAST HDL_TAP TRUE
J 2
(-950 325);
DISPLAY 0.872340 (-950 325);
DISPLAY INVISIBLE (-950 325);
FORCEPROP 1 LAST PATH I165
J 2
(-623 450);
DISPLAY 0.872340 (-623 450);
PAINT GREEN (-623 450);
DISPLAY INVISIBLE (-623 450);
FORCEADD TAP..1
R 2
(-625 400);
FORCEPROP 3 LASTPIN (-575 400) SIG_NAME M_A_CPU0_SB_CB<3>
J 0
(-565 410);
DISPLAY 0.659574 (-565 410);
PAINT MONO (-565 410);
DISPLAY INVISIBLE (-565 410);
FORCEPROP 1 LASTPIN (-575 400) BN 3
J 2
(-563 408);
DISPLAY 0.680851 (-563 408);
PAINT GREEN (-563 408);
FORCEPROP 2 LAST CDS_LIB standard
J 0
(-625 400);
DISPLAY INVISIBLE (-625 400);
FORCEPROP 1 LAST BODY_TYPE PLUMBING
J 2
(-625 450);
DISPLAY 0.872340 (-625 450);
PAINT GREEN (-625 450);
DISPLAY INVISIBLE (-625 450);
FORCEPROP 1 LAST HDL_TAP TRUE
J 2
(-950 275);
DISPLAY 0.872340 (-950 275);
DISPLAY INVISIBLE (-950 275);
FORCEPROP 1 LAST PATH I166
J 2
(-623 400);
DISPLAY 0.872340 (-623 400);
PAINT GREEN (-623 400);
DISPLAY INVISIBLE (-623 400);
FORCEADD TAP..1
R 2
(-625 350);
FORCEPROP 3 LASTPIN (-575 350) SIG_NAME M_A_CPU0_SB_CB<2>
J 0
(-565 360);
DISPLAY 0.659574 (-565 360);
PAINT MONO (-565 360);
DISPLAY INVISIBLE (-565 360);
FORCEPROP 1 LASTPIN (-575 350) BN 2
J 2
(-563 358);
DISPLAY 0.680851 (-563 358);
PAINT GREEN (-563 358);
FORCEPROP 2 LAST CDS_LIB standard
J 0
(-625 350);
DISPLAY INVISIBLE (-625 350);
FORCEPROP 1 LAST BODY_TYPE PLUMBING
J 2
(-625 400);
DISPLAY 0.872340 (-625 400);
PAINT GREEN (-625 400);
DISPLAY INVISIBLE (-625 400);
FORCEPROP 1 LAST HDL_TAP TRUE
J 2
(-950 225);
DISPLAY 0.872340 (-950 225);
DISPLAY INVISIBLE (-950 225);
FORCEPROP 1 LAST PATH I167
J 2
(-623 350);
DISPLAY 0.872340 (-623 350);
PAINT GREEN (-623 350);
DISPLAY INVISIBLE (-623 350);
FORCEADD TAP..1
R 2
(-625 300);
FORCEPROP 3 LASTPIN (-575 300) SIG_NAME M_A_CPU0_SB_CB<1>
J 0
(-565 310);
DISPLAY 0.659574 (-565 310);
PAINT MONO (-565 310);
DISPLAY INVISIBLE (-565 310);
FORCEPROP 1 LASTPIN (-575 300) BN 1
J 2
(-563 308);
DISPLAY 0.680851 (-563 308);
PAINT GREEN (-563 308);
FORCEPROP 2 LAST CDS_LIB standard
J 0
(-625 300);
DISPLAY INVISIBLE (-625 300);
FORCEPROP 1 LAST BODY_TYPE PLUMBING
J 2
(-625 350);
DISPLAY 0.872340 (-625 350);
PAINT GREEN (-625 350);
DISPLAY INVISIBLE (-625 350);
FORCEPROP 1 LAST HDL_TAP TRUE
J 2
(-950 175);
DISPLAY 0.872340 (-950 175);
DISPLAY INVISIBLE (-950 175);
FORCEPROP 1 LAST PATH I168
J 2
(-623 300);
DISPLAY 0.872340 (-623 300);
PAINT GREEN (-623 300);
DISPLAY INVISIBLE (-623 300);
FORCEADD TAP..1
R 2
(-625 250);
FORCEPROP 3 LASTPIN (-575 250) SIG_NAME M_A_CPU0_SB_CB<0>
J 0
(-565 260);
DISPLAY 0.659574 (-565 260);
PAINT MONO (-565 260);
DISPLAY INVISIBLE (-565 260);
FORCEPROP 1 LASTPIN (-575 250) BN 0
J 2
(-563 258);
DISPLAY 0.680851 (-563 258);
PAINT GREEN (-563 258);
FORCEPROP 2 LAST CDS_LIB standard
J 0
(-625 250);
DISPLAY INVISIBLE (-625 250);
FORCEPROP 1 LAST BODY_TYPE PLUMBING
J 2
(-625 300);
DISPLAY 0.872340 (-625 300);
PAINT GREEN (-625 300);
DISPLAY INVISIBLE (-625 300);
FORCEPROP 1 LAST HDL_TAP TRUE
J 2
(-950 125);
DISPLAY 0.872340 (-950 125);
DISPLAY INVISIBLE (-950 125);
FORCEPROP 1 LAST PATH I169
J 2
(-623 250);
DISPLAY 0.872340 (-623 250);
PAINT GREEN (-623 250);
DISPLAY INVISIBLE (-623 250);
FORCEADD TAP..1
R 2
(-625 3800);
FORCEPROP 3 LASTPIN (-575 3800) SIG_NAME M_A_CPU0_SA_DQ<23>
J 0
(-565 3810);
DISPLAY 0.659574 (-565 3810);
PAINT MONO (-565 3810);
DISPLAY INVISIBLE (-565 3810);
FORCEPROP 1 LASTPIN (-575 3800) BN 23
J 2
(-563 3808);
DISPLAY 0.680851 (-563 3808);
PAINT GREEN (-563 3808);
FORCEPROP 2 LAST CDS_LIB standard
J 0
(-625 3800);
DISPLAY INVISIBLE (-625 3800);
FORCEPROP 1 LAST BODY_TYPE PLUMBING
J 2
(-625 3850);
DISPLAY 0.872340 (-625 3850);
PAINT GREEN (-625 3850);
DISPLAY INVISIBLE (-625 3850);
FORCEPROP 1 LAST HDL_TAP TRUE
J 2
(-950 3675);
DISPLAY 0.872340 (-950 3675);
DISPLAY INVISIBLE (-950 3675);
FORCEPROP 1 LAST PATH I17
J 2
(-623 3800);
DISPLAY 0.872340 (-623 3800);
PAINT GREEN (-623 3800);
DISPLAY INVISIBLE (-623 3800);
FORCEADD OFFPAGE..3
R 2
(-1650 625);
FORCEPROP 2 LAST $XR1 83 
J 0
(-2019 625);
DISPLAY 0.638298 (-2019 625);
PAINT MONO (-2019 625);
FORCEPROP 2 LAST $XR0 82 
J 0
(-1929 625);
DISPLAY 0.638298 (-1929 625);
PAINT MONO (-1929 625);
FORCEPROP 2 LAST CDS_LIB standard
J 0
(-1650 625);
DISPLAY INVISIBLE (-1650 625);
FORCEPROP 1 LAST OFFPAGE TRUE
J 2
(-1975 500);
DISPLAY 0.872340 (-1975 500);
DISPLAY INVISIBLE (-1975 500);
FORCEPROP 1 LAST COMMENT_BODY TRUE
J 2
(-1600 525);
DISPLAY 0.872340 (-1600 525);
PAINT GREEN (-1600 525);
DISPLAY INVISIBLE (-1600 525);
FORCEPROP 2 LAST PATH I170
J 0
(-1975 675);
DISPLAY 1.021277 (-1975 675);
DISPLAY INVISIBLE (-1975 675);
FORCEADD TAP..1
R 2
(-625 150);
FORCEPROP 3 LASTPIN (-575 150) SIG_NAME M_A_CPU0_CLK_DP<1>
J 0
(-565 160);
DISPLAY 0.659574 (-565 160);
PAINT MONO (-565 160);
DISPLAY INVISIBLE (-565 160);
FORCEPROP 1 LASTPIN (-575 150) BN 1
J 2
(-563 158);
DISPLAY 0.680851 (-563 158);
PAINT GREEN (-563 158);
FORCEPROP 2 LAST CDS_LIB standard
J 0
(-625 150);
DISPLAY INVISIBLE (-625 150);
FORCEPROP 1 LAST BODY_TYPE PLUMBING
J 2
(-625 200);
DISPLAY 0.872340 (-625 200);
PAINT GREEN (-625 200);
DISPLAY INVISIBLE (-625 200);
FORCEPROP 1 LAST HDL_TAP TRUE
J 2
(-950 25);
DISPLAY 0.872340 (-950 25);
DISPLAY INVISIBLE (-950 25);
FORCEPROP 1 LAST PATH I171
J 2
(-623 150);
DISPLAY 0.872340 (-623 150);
PAINT GREEN (-623 150);
DISPLAY INVISIBLE (-623 150);
FORCEADD TAP..1
R 2
(-625 100);
FORCEPROP 3 LASTPIN (-575 100) SIG_NAME M_A_CPU0_CLK_DP<0>
J 0
(-565 110);
DISPLAY 0.659574 (-565 110);
PAINT MONO (-565 110);
DISPLAY INVISIBLE (-565 110);
FORCEPROP 1 LASTPIN (-575 100) BN 0
J 2
(-563 108);
DISPLAY 0.680851 (-563 108);
PAINT GREEN (-563 108);
FORCEPROP 2 LAST CDS_LIB standard
J 0
(-625 100);
DISPLAY INVISIBLE (-625 100);
FORCEPROP 1 LAST BODY_TYPE PLUMBING
J 2
(-625 150);
DISPLAY 0.872340 (-625 150);
PAINT GREEN (-625 150);
DISPLAY INVISIBLE (-625 150);
FORCEPROP 1 LAST HDL_TAP TRUE
J 2
(-950 -25);
DISPLAY 0.872340 (-950 -25);
DISPLAY INVISIBLE (-950 -25);
FORCEPROP 1 LAST PATH I172
J 2
(-623 100);
DISPLAY 0.872340 (-623 100);
PAINT GREEN (-623 100);
DISPLAY INVISIBLE (-623 100);
FORCEADD TAP..1
R 2
(-625 50);
FORCEPROP 3 LASTPIN (-575 50) SIG_NAME M_A_CPU0_CLK_DN<1>
J 0
(-565 60);
DISPLAY 0.659574 (-565 60);
PAINT MONO (-565 60);
DISPLAY INVISIBLE (-565 60);
FORCEPROP 1 LASTPIN (-575 50) BN 1
J 2
(-563 58);
DISPLAY 0.680851 (-563 58);
PAINT GREEN (-563 58);
FORCEPROP 2 LAST CDS_LIB standard
J 0
(-625 50);
DISPLAY INVISIBLE (-625 50);
FORCEPROP 1 LAST BODY_TYPE PLUMBING
J 2
(-625 100);
DISPLAY 0.872340 (-625 100);
PAINT GREEN (-625 100);
DISPLAY INVISIBLE (-625 100);
FORCEPROP 1 LAST HDL_TAP TRUE
J 2
(-950 -75);
DISPLAY 0.872340 (-950 -75);
DISPLAY INVISIBLE (-950 -75);
FORCEPROP 1 LAST PATH I175
J 2
(-623 50);
DISPLAY 0.872340 (-623 50);
PAINT GREEN (-623 50);
DISPLAY INVISIBLE (-623 50);
FORCEADD TAP..1
R 2
(-625 0);
FORCEPROP 3 LASTPIN (-575 0) SIG_NAME M_A_CPU0_CLK_DN<0>
J 0
(-565 10);
DISPLAY 0.659574 (-565 10);
PAINT MONO (-565 10);
DISPLAY INVISIBLE (-565 10);
FORCEPROP 1 LASTPIN (-575 0) BN 0
J 2
(-563 8);
DISPLAY 0.680851 (-563 8);
PAINT GREEN (-563 8);
FORCEPROP 2 LAST CDS_LIB standard
J 0
(-625 0);
DISPLAY INVISIBLE (-625 0);
FORCEPROP 1 LAST BODY_TYPE PLUMBING
J 2
(-625 50);
DISPLAY 0.872340 (-625 50);
PAINT GREEN (-625 50);
DISPLAY INVISIBLE (-625 50);
FORCEPROP 1 LAST HDL_TAP TRUE
J 2
(-950 -125);
DISPLAY 0.872340 (-950 -125);
DISPLAY INVISIBLE (-950 -125);
FORCEPROP 1 LAST PATH I176
J 2
(-623 0);
DISPLAY 0.872340 (-623 0);
PAINT GREEN (-623 0);
DISPLAY INVISIBLE (-623 0);
FORCEADD OFFPAGE..2
R 2
(-1650 75);
FORCEPROP 2 LAST $XR1 83 
J 0
(-1994 75);
DISPLAY 0.638298 (-1994 75);
PAINT MONO (-1994 75);
FORCEPROP 2 LAST $XR0 82 
J 0
(-1904 75);
DISPLAY 0.638298 (-1904 75);
PAINT MONO (-1904 75);
FORCEPROP 2 LAST CDS_LIB standard
J 0
(-1650 75);
PAINT MONO (-1650 75);
DISPLAY INVISIBLE (-1650 75);
FORCEPROP 1 LAST OFFPAGE TRUE
J 2
(-1975 -50);
DISPLAY 0.872340 (-1975 -50);
DISPLAY INVISIBLE (-1975 -50);
FORCEPROP 1 LAST COMMENT_BODY TRUE
J 2
(-1605 -20);
DISPLAY 0.872340 (-1605 -20);
PAINT GREEN (-1605 -20);
DISPLAY INVISIBLE (-1605 -20);
FORCEPROP 2 LAST PATH I177
J 0
(-1600 150);
DISPLAY 1.021277 (-1600 150);
DISPLAY INVISIBLE (-1600 150);
FORCEADD OFFPAGE..2
R 2
(-1650 175);
FORCEPROP 2 LAST $XR1 83 
J 0
(-1994 175);
DISPLAY 0.638298 (-1994 175);
PAINT MONO (-1994 175);
FORCEPROP 2 LAST $XR0 82 
J 0
(-1904 175);
DISPLAY 0.638298 (-1904 175);
PAINT MONO (-1904 175);
FORCEPROP 2 LAST CDS_LIB standard
J 0
(-1650 175);
PAINT MONO (-1650 175);
DISPLAY INVISIBLE (-1650 175);
FORCEPROP 1 LAST OFFPAGE TRUE
J 2
(-1975 50);
DISPLAY 0.872340 (-1975 50);
DISPLAY INVISIBLE (-1975 50);
FORCEPROP 1 LAST COMMENT_BODY TRUE
J 2
(-1605 80);
DISPLAY 0.872340 (-1605 80);
PAINT GREEN (-1605 80);
DISPLAY INVISIBLE (-1605 80);
FORCEPROP 2 LAST PATH I178
J 0
(-1600 250);
DISPLAY 1.021277 (-1600 250);
DISPLAY INVISIBLE (-1600 250);
FORCEADD TAP..1
R 2
(-625 3900);
FORCEPROP 3 LASTPIN (-575 3900) SIG_NAME M_A_CPU0_SA_DQ<25>
J 0
(-565 3910);
DISPLAY 0.659574 (-565 3910);
PAINT MONO (-565 3910);
DISPLAY INVISIBLE (-565 3910);
FORCEPROP 1 LASTPIN (-575 3900) BN 25
J 2
(-563 3908);
DISPLAY 0.680851 (-563 3908);
PAINT GREEN (-563 3908);
FORCEPROP 2 LAST CDS_LIB standard
J 0
(-625 3900);
DISPLAY INVISIBLE (-625 3900);
FORCEPROP 1 LAST BODY_TYPE PLUMBING
J 2
(-625 3950);
DISPLAY 0.872340 (-625 3950);
PAINT GREEN (-625 3950);
DISPLAY INVISIBLE (-625 3950);
FORCEPROP 1 LAST HDL_TAP TRUE
J 2
(-950 3775);
DISPLAY 0.872340 (-950 3775);
DISPLAY INVISIBLE (-950 3775);
FORCEPROP 1 LAST PATH I18
J 2
(-623 3900);
DISPLAY 0.872340 (-623 3900);
PAINT GREEN (-623 3900);
DISPLAY INVISIBLE (-623 3900);
FORCEADD TAP..1
R 2
(-625 3950);
FORCEPROP 3 LASTPIN (-575 3950) SIG_NAME M_A_CPU0_SA_DQ<26>
J 0
(-565 3960);
DISPLAY 0.659574 (-565 3960);
PAINT MONO (-565 3960);
DISPLAY INVISIBLE (-565 3960);
FORCEPROP 1 LASTPIN (-575 3950) BN 26
J 2
(-563 3958);
DISPLAY 0.680851 (-563 3958);
PAINT GREEN (-563 3958);
FORCEPROP 2 LAST CDS_LIB standard
J 0
(-625 3950);
DISPLAY INVISIBLE (-625 3950);
FORCEPROP 1 LAST BODY_TYPE PLUMBING
J 2
(-625 4000);
DISPLAY 0.872340 (-625 4000);
PAINT GREEN (-625 4000);
DISPLAY INVISIBLE (-625 4000);
FORCEPROP 1 LAST HDL_TAP TRUE
J 2
(-950 3825);
DISPLAY 0.872340 (-950 3825);
DISPLAY INVISIBLE (-950 3825);
FORCEPROP 1 LAST PATH I19
J 2
(-623 3950);
DISPLAY 0.872340 (-623 3950);
PAINT GREEN (-623 3950);
DISPLAY INVISIBLE (-623 3950);
FORCEADD OFFPAGE..3
R 2
(-1650 4225);
FORCEPROP 2 LAST $XR1 83 
J 0
(-2019 4225);
DISPLAY 0.638298 (-2019 4225);
PAINT MONO (-2019 4225);
FORCEPROP 2 LAST $XR0 82 
J 0
(-1929 4225);
DISPLAY 0.638298 (-1929 4225);
PAINT MONO (-1929 4225);
FORCEPROP 2 LAST CDS_LIB standard
J 0
(-1650 4225);
DISPLAY INVISIBLE (-1650 4225);
FORCEPROP 1 LAST OFFPAGE TRUE
J 2
(-1975 4100);
DISPLAY 0.872340 (-1975 4100);
DISPLAY INVISIBLE (-1975 4100);
FORCEPROP 1 LAST COMMENT_BODY TRUE
J 2
(-1600 4125);
DISPLAY 0.872340 (-1600 4125);
PAINT GREEN (-1600 4125);
DISPLAY INVISIBLE (-1600 4125);
FORCEPROP 2 LAST PATH I2
J 0
(-1975 4275);
DISPLAY 1.021277 (-1975 4275);
DISPLAY INVISIBLE (-1975 4275);
FORCEADD TAP..1
R 2
(-625 4050);
FORCEPROP 3 LASTPIN (-575 4050) SIG_NAME M_A_CPU0_SA_DQ<28>
J 0
(-565 4060);
DISPLAY 0.659574 (-565 4060);
PAINT MONO (-565 4060);
DISPLAY INVISIBLE (-565 4060);
FORCEPROP 1 LASTPIN (-575 4050) BN 28
J 2
(-563 4058);
DISPLAY 0.680851 (-563 4058);
PAINT GREEN (-563 4058);
FORCEPROP 2 LAST CDS_LIB standard
J 0
(-625 4050);
DISPLAY INVISIBLE (-625 4050);
FORCEPROP 1 LAST BODY_TYPE PLUMBING
J 2
(-625 4100);
DISPLAY 0.872340 (-625 4100);
PAINT GREEN (-625 4100);
DISPLAY INVISIBLE (-625 4100);
FORCEPROP 1 LAST HDL_TAP TRUE
J 2
(-950 3925);
DISPLAY 0.872340 (-950 3925);
DISPLAY INVISIBLE (-950 3925);
FORCEPROP 1 LAST PATH I20
J 2
(-623 4050);
DISPLAY 0.872340 (-623 4050);
PAINT GREEN (-623 4050);
DISPLAY INVISIBLE (-623 4050);
FORCEADD TAP..1
R 2
(-625 4000);
FORCEPROP 3 LASTPIN (-575 4000) SIG_NAME M_A_CPU0_SA_DQ<27>
J 0
(-565 4010);
DISPLAY 0.659574 (-565 4010);
PAINT MONO (-565 4010);
DISPLAY INVISIBLE (-565 4010);
FORCEPROP 1 LASTPIN (-575 4000) BN 27
J 2
(-563 4008);
DISPLAY 0.680851 (-563 4008);
PAINT GREEN (-563 4008);
FORCEPROP 2 LAST CDS_LIB standard
J 0
(-625 4000);
DISPLAY INVISIBLE (-625 4000);
FORCEPROP 1 LAST BODY_TYPE PLUMBING
J 2
(-625 4050);
DISPLAY 0.872340 (-625 4050);
PAINT GREEN (-625 4050);
DISPLAY INVISIBLE (-625 4050);
FORCEPROP 1 LAST HDL_TAP TRUE
J 2
(-950 3875);
DISPLAY 0.872340 (-950 3875);
DISPLAY INVISIBLE (-950 3875);
FORCEPROP 1 LAST PATH I21
J 2
(-623 4000);
DISPLAY 0.872340 (-623 4000);
PAINT GREEN (-623 4000);
DISPLAY INVISIBLE (-623 4000);
FORCEADD TAP..1
R 2
(-625 4100);
FORCEPROP 3 LASTPIN (-575 4100) SIG_NAME M_A_CPU0_SA_DQ<29>
J 0
(-565 4110);
DISPLAY 0.659574 (-565 4110);
PAINT MONO (-565 4110);
DISPLAY INVISIBLE (-565 4110);
FORCEPROP 1 LASTPIN (-575 4100) BN 29
J 2
(-563 4108);
DISPLAY 0.680851 (-563 4108);
PAINT GREEN (-563 4108);
FORCEPROP 2 LAST CDS_LIB standard
J 0
(-625 4100);
DISPLAY INVISIBLE (-625 4100);
FORCEPROP 1 LAST BODY_TYPE PLUMBING
J 2
(-625 4150);
DISPLAY 0.872340 (-625 4150);
PAINT GREEN (-625 4150);
DISPLAY INVISIBLE (-625 4150);
FORCEPROP 1 LAST HDL_TAP TRUE
J 2
(-950 3975);
DISPLAY 0.872340 (-950 3975);
DISPLAY INVISIBLE (-950 3975);
FORCEPROP 1 LAST PATH I22
J 2
(-623 4100);
DISPLAY 0.872340 (-623 4100);
PAINT GREEN (-623 4100);
DISPLAY INVISIBLE (-623 4100);
FORCEADD TAP..1
R 2
(-625 4150);
FORCEPROP 3 LASTPIN (-575 4150) SIG_NAME M_A_CPU0_SA_DQ<30>
J 0
(-565 4160);
DISPLAY 0.659574 (-565 4160);
PAINT MONO (-565 4160);
DISPLAY INVISIBLE (-565 4160);
FORCEPROP 1 LASTPIN (-575 4150) BN 30
J 2
(-563 4158);
DISPLAY 0.680851 (-563 4158);
PAINT GREEN (-563 4158);
FORCEPROP 2 LAST CDS_LIB standard
J 0
(-625 4150);
DISPLAY INVISIBLE (-625 4150);
FORCEPROP 1 LAST BODY_TYPE PLUMBING
J 2
(-625 4200);
DISPLAY 0.872340 (-625 4200);
PAINT GREEN (-625 4200);
DISPLAY INVISIBLE (-625 4200);
FORCEPROP 1 LAST HDL_TAP TRUE
J 2
(-950 4025);
DISPLAY 0.872340 (-950 4025);
DISPLAY INVISIBLE (-950 4025);
FORCEPROP 1 LAST PATH I23
J 2
(-623 4150);
DISPLAY 0.872340 (-623 4150);
PAINT GREEN (-623 4150);
DISPLAY INVISIBLE (-623 4150);
FORCEADD TAP..1
R 2
(-625 4200);
FORCEPROP 3 LASTPIN (-575 4200) SIG_NAME M_A_CPU0_SA_DQ<31>
J 0
(-565 4210);
DISPLAY 0.659574 (-565 4210);
PAINT MONO (-565 4210);
DISPLAY INVISIBLE (-565 4210);
FORCEPROP 1 LASTPIN (-575 4200) BN 31
J 2
(-563 4208);
DISPLAY 0.680851 (-563 4208);
PAINT GREEN (-563 4208);
FORCEPROP 2 LAST CDS_LIB standard
J 0
(-625 4200);
DISPLAY INVISIBLE (-625 4200);
FORCEPROP 1 LAST BODY_TYPE PLUMBING
J 2
(-625 4250);
DISPLAY 0.872340 (-625 4250);
PAINT GREEN (-625 4250);
DISPLAY INVISIBLE (-625 4250);
FORCEPROP 1 LAST HDL_TAP TRUE
J 2
(-950 4075);
DISPLAY 0.872340 (-950 4075);
DISPLAY INVISIBLE (-950 4075);
FORCEPROP 1 LAST PATH I24
J 2
(-623 4200);
DISPLAY 0.872340 (-623 4200);
PAINT GREEN (-623 4200);
DISPLAY INVISIBLE (-623 4200);
FORCEADD TAP..1
R 2
(-625 2800);
FORCEPROP 3 LASTPIN (-575 2800) SIG_NAME M_A_CPU0_SA_DQ<3>
J 0
(-565 2810);
DISPLAY 0.659574 (-565 2810);
PAINT MONO (-565 2810);
DISPLAY INVISIBLE (-565 2810);
FORCEPROP 1 LASTPIN (-575 2800) BN 3
J 2
(-563 2808);
DISPLAY 0.680851 (-563 2808);
PAINT GREEN (-563 2808);
FORCEPROP 2 LAST CDS_LIB standard
J 0
(-625 2800);
DISPLAY INVISIBLE (-625 2800);
FORCEPROP 1 LAST BODY_TYPE PLUMBING
J 2
(-625 2850);
DISPLAY 0.872340 (-625 2850);
PAINT GREEN (-625 2850);
DISPLAY INVISIBLE (-625 2850);
FORCEPROP 1 LAST HDL_TAP TRUE
J 2
(-950 2675);
DISPLAY 0.872340 (-950 2675);
DISPLAY INVISIBLE (-950 2675);
FORCEPROP 1 LAST PATH I25
J 2
(-623 2800);
DISPLAY 0.872340 (-623 2800);
PAINT GREEN (-623 2800);
DISPLAY INVISIBLE (-623 2800);
FORCEADD TAP..1
R 2
(-625 2850);
FORCEPROP 3 LASTPIN (-575 2850) SIG_NAME M_A_CPU0_SA_DQ<4>
J 0
(-565 2860);
DISPLAY 0.659574 (-565 2860);
PAINT MONO (-565 2860);
DISPLAY INVISIBLE (-565 2860);
FORCEPROP 1 LASTPIN (-575 2850) BN 4
J 2
(-563 2858);
DISPLAY 0.680851 (-563 2858);
PAINT GREEN (-563 2858);
FORCEPROP 2 LAST CDS_LIB standard
J 0
(-625 2850);
DISPLAY INVISIBLE (-625 2850);
FORCEPROP 1 LAST BODY_TYPE PLUMBING
J 2
(-625 2900);
DISPLAY 0.872340 (-625 2900);
PAINT GREEN (-625 2900);
DISPLAY INVISIBLE (-625 2900);
FORCEPROP 1 LAST HDL_TAP TRUE
J 2
(-950 2725);
DISPLAY 0.872340 (-950 2725);
DISPLAY INVISIBLE (-950 2725);
FORCEPROP 1 LAST PATH I26
J 2
(-623 2850);
DISPLAY 0.872340 (-623 2850);
PAINT GREEN (-623 2850);
DISPLAY INVISIBLE (-623 2850);
FORCEADD TAP..1
R 2
(-625 2900);
FORCEPROP 3 LASTPIN (-575 2900) SIG_NAME M_A_CPU0_SA_DQ<5>
J 0
(-565 2910);
DISPLAY 0.659574 (-565 2910);
PAINT MONO (-565 2910);
DISPLAY INVISIBLE (-565 2910);
FORCEPROP 1 LASTPIN (-575 2900) BN 5
J 2
(-563 2908);
DISPLAY 0.680851 (-563 2908);
PAINT GREEN (-563 2908);
FORCEPROP 2 LAST CDS_LIB standard
J 0
(-625 2900);
DISPLAY INVISIBLE (-625 2900);
FORCEPROP 1 LAST BODY_TYPE PLUMBING
J 2
(-625 2950);
DISPLAY 0.872340 (-625 2950);
PAINT GREEN (-625 2950);
DISPLAY INVISIBLE (-625 2950);
FORCEPROP 1 LAST HDL_TAP TRUE
J 2
(-950 2775);
DISPLAY 0.872340 (-950 2775);
DISPLAY INVISIBLE (-950 2775);
FORCEPROP 1 LAST PATH I27
J 2
(-623 2900);
DISPLAY 0.872340 (-623 2900);
PAINT GREEN (-623 2900);
DISPLAY INVISIBLE (-623 2900);
FORCEADD TAP..1
R 2
(-625 2950);
FORCEPROP 3 LASTPIN (-575 2950) SIG_NAME M_A_CPU0_SA_DQ<6>
J 0
(-565 2960);
DISPLAY 0.659574 (-565 2960);
PAINT MONO (-565 2960);
DISPLAY INVISIBLE (-565 2960);
FORCEPROP 1 LASTPIN (-575 2950) BN 6
J 2
(-563 2958);
DISPLAY 0.680851 (-563 2958);
PAINT GREEN (-563 2958);
FORCEPROP 2 LAST CDS_LIB standard
J 0
(-625 2950);
DISPLAY INVISIBLE (-625 2950);
FORCEPROP 1 LAST BODY_TYPE PLUMBING
J 2
(-625 3000);
DISPLAY 0.872340 (-625 3000);
PAINT GREEN (-625 3000);
DISPLAY INVISIBLE (-625 3000);
FORCEPROP 1 LAST HDL_TAP TRUE
J 2
(-950 2825);
DISPLAY 0.872340 (-950 2825);
DISPLAY INVISIBLE (-950 2825);
FORCEPROP 1 LAST PATH I28
J 2
(-623 2950);
DISPLAY 0.872340 (-623 2950);
PAINT GREEN (-623 2950);
DISPLAY INVISIBLE (-623 2950);
FORCEADD TAP..1
R 2
(-625 3000);
FORCEPROP 3 LASTPIN (-575 3000) SIG_NAME M_A_CPU0_SA_DQ<7>
J 0
(-565 3010);
DISPLAY 0.659574 (-565 3010);
PAINT MONO (-565 3010);
DISPLAY INVISIBLE (-565 3010);
FORCEPROP 1 LASTPIN (-575 3000) BN 7
J 2
(-563 3008);
DISPLAY 0.680851 (-563 3008);
PAINT GREEN (-563 3008);
FORCEPROP 2 LAST CDS_LIB standard
J 0
(-625 3000);
DISPLAY INVISIBLE (-625 3000);
FORCEPROP 1 LAST BODY_TYPE PLUMBING
J 2
(-625 3050);
DISPLAY 0.872340 (-625 3050);
PAINT GREEN (-625 3050);
DISPLAY INVISIBLE (-625 3050);
FORCEPROP 1 LAST HDL_TAP TRUE
J 2
(-950 2875);
DISPLAY 0.872340 (-950 2875);
DISPLAY INVISIBLE (-950 2875);
FORCEPROP 1 LAST PATH I29
J 2
(-623 3000);
DISPLAY 0.872340 (-623 3000);
PAINT GREEN (-623 3000);
DISPLAY INVISIBLE (-623 3000);
FORCEADD TAP..1
R 2
(-625 2750);
FORCEPROP 3 LASTPIN (-575 2750) SIG_NAME M_A_CPU0_SA_DQ<2>
J 0
(-565 2760);
DISPLAY 0.659574 (-565 2760);
PAINT MONO (-565 2760);
DISPLAY INVISIBLE (-565 2760);
FORCEPROP 1 LASTPIN (-575 2750) BN 2
J 2
(-563 2758);
DISPLAY 0.680851 (-563 2758);
PAINT GREEN (-563 2758);
FORCEPROP 2 LAST CDS_LIB standard
J 0
(-625 2750);
DISPLAY INVISIBLE (-625 2750);
FORCEPROP 1 LAST BODY_TYPE PLUMBING
J 2
(-625 2800);
DISPLAY 0.872340 (-625 2800);
PAINT GREEN (-625 2800);
DISPLAY INVISIBLE (-625 2800);
FORCEPROP 1 LAST HDL_TAP TRUE
J 2
(-950 2625);
DISPLAY 0.872340 (-950 2625);
DISPLAY INVISIBLE (-950 2625);
FORCEPROP 1 LAST PATH I3
J 2
(-623 2750);
DISPLAY 0.872340 (-623 2750);
PAINT GREEN (-623 2750);
DISPLAY INVISIBLE (-623 2750);
FORCEADD TAP..1
R 2
(-625 3050);
FORCEPROP 3 LASTPIN (-575 3050) SIG_NAME M_A_CPU0_SA_DQ<8>
J 0
(-565 3060);
DISPLAY 0.659574 (-565 3060);
PAINT MONO (-565 3060);
DISPLAY INVISIBLE (-565 3060);
FORCEPROP 1 LASTPIN (-575 3050) BN 8
J 2
(-563 3058);
DISPLAY 0.680851 (-563 3058);
PAINT GREEN (-563 3058);
FORCEPROP 2 LAST CDS_LIB standard
J 0
(-625 3050);
DISPLAY INVISIBLE (-625 3050);
FORCEPROP 1 LAST BODY_TYPE PLUMBING
J 2
(-625 3100);
DISPLAY 0.872340 (-625 3100);
PAINT GREEN (-625 3100);
DISPLAY INVISIBLE (-625 3100);
FORCEPROP 1 LAST HDL_TAP TRUE
J 2
(-950 2925);
DISPLAY 0.872340 (-950 2925);
DISPLAY INVISIBLE (-950 2925);
FORCEPROP 1 LAST PATH I30
J 2
(-623 3050);
DISPLAY 0.872340 (-623 3050);
PAINT GREEN (-623 3050);
DISPLAY INVISIBLE (-623 3050);
FORCEADD TAP..1
R 2
(-625 3100);
FORCEPROP 3 LASTPIN (-575 3100) SIG_NAME M_A_CPU0_SA_DQ<9>
J 0
(-565 3110);
DISPLAY 0.659574 (-565 3110);
PAINT MONO (-565 3110);
DISPLAY INVISIBLE (-565 3110);
FORCEPROP 1 LASTPIN (-575 3100) BN 9
J 2
(-563 3108);
DISPLAY 0.680851 (-563 3108);
PAINT GREEN (-563 3108);
FORCEPROP 2 LAST CDS_LIB standard
J 0
(-625 3100);
DISPLAY INVISIBLE (-625 3100);
FORCEPROP 1 LAST BODY_TYPE PLUMBING
J 2
(-625 3150);
DISPLAY 0.872340 (-625 3150);
PAINT GREEN (-625 3150);
DISPLAY INVISIBLE (-625 3150);
FORCEPROP 1 LAST HDL_TAP TRUE
J 2
(-950 2975);
DISPLAY 0.872340 (-950 2975);
DISPLAY INVISIBLE (-950 2975);
FORCEPROP 1 LAST PATH I31
J 2
(-623 3100);
DISPLAY 0.872340 (-623 3100);
PAINT GREEN (-623 3100);
DISPLAY INVISIBLE (-623 3100);
FORCEADD TAP..1
R 2
(-625 3150);
FORCEPROP 3 LASTPIN (-575 3150) SIG_NAME M_A_CPU0_SA_DQ<10>
J 0
(-565 3160);
DISPLAY 0.659574 (-565 3160);
PAINT MONO (-565 3160);
DISPLAY INVISIBLE (-565 3160);
FORCEPROP 1 LASTPIN (-575 3150) BN 10
J 2
(-563 3158);
DISPLAY 0.680851 (-563 3158);
PAINT GREEN (-563 3158);
FORCEPROP 2 LAST CDS_LIB standard
J 0
(-625 3150);
DISPLAY INVISIBLE (-625 3150);
FORCEPROP 1 LAST BODY_TYPE PLUMBING
J 2
(-625 3200);
DISPLAY 0.872340 (-625 3200);
PAINT GREEN (-625 3200);
DISPLAY INVISIBLE (-625 3200);
FORCEPROP 1 LAST HDL_TAP TRUE
J 2
(-950 3025);
DISPLAY 0.872340 (-950 3025);
DISPLAY INVISIBLE (-950 3025);
FORCEPROP 1 LAST PATH I32
J 2
(-623 3150);
DISPLAY 0.872340 (-623 3150);
PAINT GREEN (-623 3150);
DISPLAY INVISIBLE (-623 3150);
FORCEADD TAP..1
R 2
(-625 2700);
FORCEPROP 3 LASTPIN (-575 2700) SIG_NAME M_A_CPU0_SA_DQ<1>
J 0
(-565 2710);
DISPLAY 0.659574 (-565 2710);
PAINT MONO (-565 2710);
DISPLAY INVISIBLE (-565 2710);
FORCEPROP 1 LASTPIN (-575 2700) BN 1
J 2
(-563 2708);
DISPLAY 0.680851 (-563 2708);
PAINT GREEN (-563 2708);
FORCEPROP 2 LAST CDS_LIB standard
J 0
(-625 2700);
DISPLAY INVISIBLE (-625 2700);
FORCEPROP 1 LAST BODY_TYPE PLUMBING
J 2
(-625 2750);
DISPLAY 0.872340 (-625 2750);
PAINT GREEN (-625 2750);
DISPLAY INVISIBLE (-625 2750);
FORCEPROP 1 LAST HDL_TAP TRUE
J 2
(-950 2575);
DISPLAY 0.872340 (-950 2575);
DISPLAY INVISIBLE (-950 2575);
FORCEPROP 1 LAST PATH I33
J 2
(-623 2700);
DISPLAY 0.872340 (-623 2700);
PAINT GREEN (-623 2700);
DISPLAY INVISIBLE (-623 2700);
FORCEADD TAP..1
R 2
(-625 2650);
FORCEPROP 3 LASTPIN (-575 2650) SIG_NAME M_A_CPU0_SA_DQ<0>
J 0
(-565 2660);
DISPLAY 0.659574 (-565 2660);
PAINT MONO (-565 2660);
DISPLAY INVISIBLE (-565 2660);
FORCEPROP 1 LASTPIN (-575 2650) BN 0
J 2
(-563 2658);
DISPLAY 0.680851 (-563 2658);
PAINT GREEN (-563 2658);
FORCEPROP 2 LAST CDS_LIB standard
J 0
(-625 2650);
DISPLAY INVISIBLE (-625 2650);
FORCEPROP 1 LAST BODY_TYPE PLUMBING
J 2
(-625 2700);
DISPLAY 0.872340 (-625 2700);
PAINT GREEN (-625 2700);
DISPLAY INVISIBLE (-625 2700);
FORCEPROP 1 LAST HDL_TAP TRUE
J 2
(-950 2525);
DISPLAY 0.872340 (-950 2525);
DISPLAY INVISIBLE (-950 2525);
FORCEPROP 1 LAST PATH I34
J 2
(-623 2650);
DISPLAY 0.872340 (-623 2650);
PAINT GREEN (-623 2650);
DISPLAY INVISIBLE (-623 2650);
FORCEADD TAP..1
R 2
(-625 2200);
FORCEPROP 3 LASTPIN (-575 2200) SIG_NAME M_A_CPU0_SB_DQ<31>
J 0
(-565 2210);
DISPLAY 0.659574 (-565 2210);
PAINT MONO (-565 2210);
DISPLAY INVISIBLE (-565 2210);
FORCEPROP 1 LASTPIN (-575 2200) BN 31
J 2
(-563 2208);
DISPLAY 0.680851 (-563 2208);
PAINT GREEN (-563 2208);
FORCEPROP 2 LAST CDS_LIB standard
J 0
(-625 2200);
DISPLAY INVISIBLE (-625 2200);
FORCEPROP 1 LAST BODY_TYPE PLUMBING
J 2
(-625 2250);
DISPLAY 0.872340 (-625 2250);
PAINT GREEN (-625 2250);
DISPLAY INVISIBLE (-625 2250);
FORCEPROP 1 LAST HDL_TAP TRUE
J 2
(-950 2075);
DISPLAY 0.872340 (-950 2075);
DISPLAY INVISIBLE (-950 2075);
FORCEPROP 1 LAST PATH I35
J 2
(-623 2200);
DISPLAY 0.872340 (-623 2200);
PAINT GREEN (-623 2200);
DISPLAY INVISIBLE (-623 2200);
FORCEADD TAP..1
R 2
(-625 2150);
FORCEPROP 3 LASTPIN (-575 2150) SIG_NAME M_A_CPU0_SB_DQ<30>
J 0
(-565 2160);
DISPLAY 0.659574 (-565 2160);
PAINT MONO (-565 2160);
DISPLAY INVISIBLE (-565 2160);
FORCEPROP 1 LASTPIN (-575 2150) BN 30
J 2
(-563 2158);
DISPLAY 0.680851 (-563 2158);
PAINT GREEN (-563 2158);
FORCEPROP 2 LAST CDS_LIB standard
J 0
(-625 2150);
DISPLAY INVISIBLE (-625 2150);
FORCEPROP 1 LAST BODY_TYPE PLUMBING
J 2
(-625 2200);
DISPLAY 0.872340 (-625 2200);
PAINT GREEN (-625 2200);
DISPLAY INVISIBLE (-625 2200);
FORCEPROP 1 LAST HDL_TAP TRUE
J 2
(-950 2025);
DISPLAY 0.872340 (-950 2025);
DISPLAY INVISIBLE (-950 2025);
FORCEPROP 1 LAST PATH I36
J 2
(-623 2150);
DISPLAY 0.872340 (-623 2150);
PAINT GREEN (-623 2150);
DISPLAY INVISIBLE (-623 2150);
FORCEADD TAP..1
R 2
(-625 2100);
FORCEPROP 3 LASTPIN (-575 2100) SIG_NAME M_A_CPU0_SB_DQ<29>
J 0
(-565 2110);
DISPLAY 0.659574 (-565 2110);
PAINT MONO (-565 2110);
DISPLAY INVISIBLE (-565 2110);
FORCEPROP 1 LASTPIN (-575 2100) BN 29
J 2
(-563 2108);
DISPLAY 0.680851 (-563 2108);
PAINT GREEN (-563 2108);
FORCEPROP 2 LAST CDS_LIB standard
J 0
(-625 2100);
DISPLAY INVISIBLE (-625 2100);
FORCEPROP 1 LAST BODY_TYPE PLUMBING
J 2
(-625 2150);
DISPLAY 0.872340 (-625 2150);
PAINT GREEN (-625 2150);
DISPLAY INVISIBLE (-625 2150);
FORCEPROP 1 LAST HDL_TAP TRUE
J 2
(-950 1975);
DISPLAY 0.872340 (-950 1975);
DISPLAY INVISIBLE (-950 1975);
FORCEPROP 1 LAST PATH I37
J 2
(-623 2100);
DISPLAY 0.872340 (-623 2100);
PAINT GREEN (-623 2100);
DISPLAY INVISIBLE (-623 2100);
FORCEADD OFFPAGE..3
R 2
(-1650 2225);
FORCEPROP 2 LAST $XR1 83 
J 0
(-2019 2225);
DISPLAY 0.638298 (-2019 2225);
PAINT MONO (-2019 2225);
FORCEPROP 2 LAST $XR0 82 
J 0
(-1929 2225);
DISPLAY 0.638298 (-1929 2225);
PAINT MONO (-1929 2225);
FORCEPROP 2 LAST CDS_LIB standard
J 0
(-1650 2225);
DISPLAY INVISIBLE (-1650 2225);
FORCEPROP 1 LAST OFFPAGE TRUE
J 2
(-1975 2100);
DISPLAY 0.872340 (-1975 2100);
DISPLAY INVISIBLE (-1975 2100);
FORCEPROP 1 LAST COMMENT_BODY TRUE
J 2
(-1600 2125);
DISPLAY 0.872340 (-1600 2125);
PAINT GREEN (-1600 2125);
DISPLAY INVISIBLE (-1600 2125);
FORCEPROP 2 LAST PATH I38
J 0
(-1975 2275);
DISPLAY 1.021277 (-1975 2275);
DISPLAY INVISIBLE (-1975 2275);
FORCEADD TAP..1
R 2
(-625 1950);
FORCEPROP 3 LASTPIN (-575 1950) SIG_NAME M_A_CPU0_SB_DQ<26>
J 0
(-565 1960);
DISPLAY 0.659574 (-565 1960);
PAINT MONO (-565 1960);
DISPLAY INVISIBLE (-565 1960);
FORCEPROP 1 LASTPIN (-575 1950) BN 26
J 2
(-563 1958);
DISPLAY 0.680851 (-563 1958);
PAINT GREEN (-563 1958);
FORCEPROP 2 LAST CDS_LIB standard
J 0
(-625 1950);
DISPLAY INVISIBLE (-625 1950);
FORCEPROP 1 LAST BODY_TYPE PLUMBING
J 2
(-625 2000);
DISPLAY 0.872340 (-625 2000);
PAINT GREEN (-625 2000);
DISPLAY INVISIBLE (-625 2000);
FORCEPROP 1 LAST HDL_TAP TRUE
J 2
(-950 1825);
DISPLAY 0.872340 (-950 1825);
DISPLAY INVISIBLE (-950 1825);
FORCEPROP 1 LAST PATH I39
J 2
(-623 1950);
DISPLAY 0.872340 (-623 1950);
PAINT GREEN (-623 1950);
DISPLAY INVISIBLE (-623 1950);
FORCEADD TAP..1
R 2
(-625 3200);
FORCEPROP 3 LASTPIN (-575 3200) SIG_NAME M_A_CPU0_SA_DQ<11>
J 0
(-565 3210);
DISPLAY 0.659574 (-565 3210);
PAINT MONO (-565 3210);
DISPLAY INVISIBLE (-565 3210);
FORCEPROP 1 LASTPIN (-575 3200) BN 11
J 2
(-563 3208);
DISPLAY 0.680851 (-563 3208);
PAINT GREEN (-563 3208);
FORCEPROP 2 LAST CDS_LIB standard
J 0
(-625 3200);
DISPLAY INVISIBLE (-625 3200);
FORCEPROP 1 LAST BODY_TYPE PLUMBING
J 2
(-625 3250);
DISPLAY 0.872340 (-625 3250);
PAINT GREEN (-625 3250);
DISPLAY INVISIBLE (-625 3250);
FORCEPROP 1 LAST HDL_TAP TRUE
J 2
(-950 3075);
DISPLAY 0.872340 (-950 3075);
DISPLAY INVISIBLE (-950 3075);
FORCEPROP 1 LAST PATH I4
J 2
(-623 3200);
DISPLAY 0.872340 (-623 3200);
PAINT GREEN (-623 3200);
DISPLAY INVISIBLE (-623 3200);
FORCEADD TAP..1
R 2
(-625 2050);
FORCEPROP 3 LASTPIN (-575 2050) SIG_NAME M_A_CPU0_SB_DQ<28>
J 0
(-565 2060);
DISPLAY 0.659574 (-565 2060);
PAINT MONO (-565 2060);
DISPLAY INVISIBLE (-565 2060);
FORCEPROP 1 LASTPIN (-575 2050) BN 28
J 2
(-563 2058);
DISPLAY 0.680851 (-563 2058);
PAINT GREEN (-563 2058);
FORCEPROP 2 LAST CDS_LIB standard
J 0
(-625 2050);
DISPLAY INVISIBLE (-625 2050);
FORCEPROP 1 LAST BODY_TYPE PLUMBING
J 2
(-625 2100);
DISPLAY 0.872340 (-625 2100);
PAINT GREEN (-625 2100);
DISPLAY INVISIBLE (-625 2100);
FORCEPROP 1 LAST HDL_TAP TRUE
J 2
(-950 1925);
DISPLAY 0.872340 (-950 1925);
DISPLAY INVISIBLE (-950 1925);
FORCEPROP 1 LAST PATH I40
J 2
(-623 2050);
DISPLAY 0.872340 (-623 2050);
PAINT GREEN (-623 2050);
DISPLAY INVISIBLE (-623 2050);
FORCEADD TAP..1
R 2
(-625 2000);
FORCEPROP 3 LASTPIN (-575 2000) SIG_NAME M_A_CPU0_SB_DQ<27>
J 0
(-565 2010);
DISPLAY 0.659574 (-565 2010);
PAINT MONO (-565 2010);
DISPLAY INVISIBLE (-565 2010);
FORCEPROP 1 LASTPIN (-575 2000) BN 27
J 2
(-563 2008);
DISPLAY 0.680851 (-563 2008);
PAINT GREEN (-563 2008);
FORCEPROP 2 LAST CDS_LIB standard
J 0
(-625 2000);
DISPLAY INVISIBLE (-625 2000);
FORCEPROP 1 LAST BODY_TYPE PLUMBING
J 2
(-625 2050);
DISPLAY 0.872340 (-625 2050);
PAINT GREEN (-625 2050);
DISPLAY INVISIBLE (-625 2050);
FORCEPROP 1 LAST HDL_TAP TRUE
J 2
(-950 1875);
DISPLAY 0.872340 (-950 1875);
DISPLAY INVISIBLE (-950 1875);
FORCEPROP 1 LAST PATH I41
J 2
(-623 2000);
DISPLAY 0.872340 (-623 2000);
PAINT GREEN (-623 2000);
DISPLAY INVISIBLE (-623 2000);
FORCEADD TAP..1
R 2
(-625 1900);
FORCEPROP 3 LASTPIN (-575 1900) SIG_NAME M_A_CPU0_SB_DQ<25>
J 0
(-565 1910);
DISPLAY 0.659574 (-565 1910);
PAINT MONO (-565 1910);
DISPLAY INVISIBLE (-565 1910);
FORCEPROP 1 LASTPIN (-575 1900) BN 25
J 2
(-563 1908);
DISPLAY 0.680851 (-563 1908);
PAINT GREEN (-563 1908);
FORCEPROP 2 LAST CDS_LIB standard
J 0
(-625 1900);
DISPLAY INVISIBLE (-625 1900);
FORCEPROP 1 LAST BODY_TYPE PLUMBING
J 2
(-625 1950);
DISPLAY 0.872340 (-625 1950);
PAINT GREEN (-625 1950);
DISPLAY INVISIBLE (-625 1950);
FORCEPROP 1 LAST HDL_TAP TRUE
J 2
(-950 1775);
DISPLAY 0.872340 (-950 1775);
DISPLAY INVISIBLE (-950 1775);
FORCEPROP 1 LAST PATH I42
J 2
(-623 1900);
DISPLAY 0.872340 (-623 1900);
PAINT GREEN (-623 1900);
DISPLAY INVISIBLE (-623 1900);
FORCEADD TAP..1
R 2
(-625 1850);
FORCEPROP 3 LASTPIN (-575 1850) SIG_NAME M_A_CPU0_SB_DQ<24>
J 0
(-565 1860);
DISPLAY 0.659574 (-565 1860);
PAINT MONO (-565 1860);
DISPLAY INVISIBLE (-565 1860);
FORCEPROP 1 LASTPIN (-575 1850) BN 24
J 2
(-563 1858);
DISPLAY 0.680851 (-563 1858);
PAINT GREEN (-563 1858);
FORCEPROP 2 LAST CDS_LIB standard
J 0
(-625 1850);
DISPLAY INVISIBLE (-625 1850);
FORCEPROP 1 LAST BODY_TYPE PLUMBING
J 2
(-625 1900);
DISPLAY 0.872340 (-625 1900);
PAINT GREEN (-625 1900);
DISPLAY INVISIBLE (-625 1900);
FORCEPROP 1 LAST HDL_TAP TRUE
J 2
(-950 1725);
DISPLAY 0.872340 (-950 1725);
DISPLAY INVISIBLE (-950 1725);
FORCEPROP 1 LAST PATH I43
J 2
(-623 1850);
DISPLAY 0.872340 (-623 1850);
PAINT GREEN (-623 1850);
DISPLAY INVISIBLE (-623 1850);
FORCEADD TAP..1
R 2
(-625 1700);
FORCEPROP 3 LASTPIN (-575 1700) SIG_NAME M_A_CPU0_SB_DQ<21>
J 0
(-565 1710);
DISPLAY 0.659574 (-565 1710);
PAINT MONO (-565 1710);
DISPLAY INVISIBLE (-565 1710);
FORCEPROP 1 LASTPIN (-575 1700) BN 21
J 2
(-563 1708);
DISPLAY 0.680851 (-563 1708);
PAINT GREEN (-563 1708);
FORCEPROP 2 LAST CDS_LIB standard
J 0
(-625 1700);
DISPLAY INVISIBLE (-625 1700);
FORCEPROP 1 LAST BODY_TYPE PLUMBING
J 2
(-625 1750);
DISPLAY 0.872340 (-625 1750);
PAINT GREEN (-625 1750);
DISPLAY INVISIBLE (-625 1750);
FORCEPROP 1 LAST HDL_TAP TRUE
J 2
(-950 1575);
DISPLAY 0.872340 (-950 1575);
DISPLAY INVISIBLE (-950 1575);
FORCEPROP 1 LAST PATH I44
J 2
(-623 1700);
DISPLAY 0.872340 (-623 1700);
PAINT GREEN (-623 1700);
DISPLAY INVISIBLE (-623 1700);
FORCEADD TAP..1
R 2
(-625 1750);
FORCEPROP 3 LASTPIN (-575 1750) SIG_NAME M_A_CPU0_SB_DQ<22>
J 0
(-565 1760);
DISPLAY 0.659574 (-565 1760);
PAINT MONO (-565 1760);
DISPLAY INVISIBLE (-565 1760);
FORCEPROP 1 LASTPIN (-575 1750) BN 22
J 2
(-563 1758);
DISPLAY 0.680851 (-563 1758);
PAINT GREEN (-563 1758);
FORCEPROP 2 LAST CDS_LIB standard
J 0
(-625 1750);
DISPLAY INVISIBLE (-625 1750);
FORCEPROP 1 LAST BODY_TYPE PLUMBING
J 2
(-625 1800);
DISPLAY 0.872340 (-625 1800);
PAINT GREEN (-625 1800);
DISPLAY INVISIBLE (-625 1800);
FORCEPROP 1 LAST HDL_TAP TRUE
J 2
(-950 1625);
DISPLAY 0.872340 (-950 1625);
DISPLAY INVISIBLE (-950 1625);
FORCEPROP 1 LAST PATH I45
J 2
(-623 1750);
DISPLAY 0.872340 (-623 1750);
PAINT GREEN (-623 1750);
DISPLAY INVISIBLE (-623 1750);
FORCEADD TAP..1
R 2
(-625 1800);
FORCEPROP 3 LASTPIN (-575 1800) SIG_NAME M_A_CPU0_SB_DQ<23>
J 0
(-565 1810);
DISPLAY 0.659574 (-565 1810);
PAINT MONO (-565 1810);
DISPLAY INVISIBLE (-565 1810);
FORCEPROP 1 LASTPIN (-575 1800) BN 23
J 2
(-563 1808);
DISPLAY 0.680851 (-563 1808);
PAINT GREEN (-563 1808);
FORCEPROP 2 LAST CDS_LIB standard
J 0
(-625 1800);
DISPLAY INVISIBLE (-625 1800);
FORCEPROP 1 LAST BODY_TYPE PLUMBING
J 2
(-625 1850);
DISPLAY 0.872340 (-625 1850);
PAINT GREEN (-625 1850);
DISPLAY INVISIBLE (-625 1850);
FORCEPROP 1 LAST HDL_TAP TRUE
J 2
(-950 1675);
DISPLAY 0.872340 (-950 1675);
DISPLAY INVISIBLE (-950 1675);
FORCEPROP 1 LAST PATH I46
J 2
(-623 1800);
DISPLAY 0.872340 (-623 1800);
PAINT GREEN (-623 1800);
DISPLAY INVISIBLE (-623 1800);
FORCEADD TAP..1
R 2
(-625 1650);
FORCEPROP 3 LASTPIN (-575 1650) SIG_NAME M_A_CPU0_SB_DQ<20>
J 0
(-565 1660);
DISPLAY 0.659574 (-565 1660);
PAINT MONO (-565 1660);
DISPLAY INVISIBLE (-565 1660);
FORCEPROP 1 LASTPIN (-575 1650) BN 20
J 2
(-563 1658);
DISPLAY 0.680851 (-563 1658);
PAINT GREEN (-563 1658);
FORCEPROP 2 LAST CDS_LIB standard
J 0
(-625 1650);
DISPLAY INVISIBLE (-625 1650);
FORCEPROP 1 LAST BODY_TYPE PLUMBING
J 2
(-625 1700);
DISPLAY 0.872340 (-625 1700);
PAINT GREEN (-625 1700);
DISPLAY INVISIBLE (-625 1700);
FORCEPROP 1 LAST HDL_TAP TRUE
J 2
(-950 1525);
DISPLAY 0.872340 (-950 1525);
DISPLAY INVISIBLE (-950 1525);
FORCEPROP 1 LAST PATH I47
J 2
(-623 1650);
DISPLAY 0.872340 (-623 1650);
PAINT GREEN (-623 1650);
DISPLAY INVISIBLE (-623 1650);
FORCEADD TAP..1
R 2
(-625 1600);
FORCEPROP 3 LASTPIN (-575 1600) SIG_NAME M_A_CPU0_SB_DQ<19>
J 0
(-565 1610);
DISPLAY 0.659574 (-565 1610);
PAINT MONO (-565 1610);
DISPLAY INVISIBLE (-565 1610);
FORCEPROP 1 LASTPIN (-575 1600) BN 19
J 2
(-563 1608);
DISPLAY 0.680851 (-563 1608);
PAINT GREEN (-563 1608);
FORCEPROP 2 LAST CDS_LIB standard
J 0
(-625 1600);
DISPLAY INVISIBLE (-625 1600);
FORCEPROP 1 LAST BODY_TYPE PLUMBING
J 2
(-625 1650);
DISPLAY 0.872340 (-625 1650);
PAINT GREEN (-625 1650);
DISPLAY INVISIBLE (-625 1650);
FORCEPROP 1 LAST HDL_TAP TRUE
J 2
(-950 1475);
DISPLAY 0.872340 (-950 1475);
DISPLAY INVISIBLE (-950 1475);
FORCEPROP 1 LAST PATH I48
J 2
(-623 1600);
DISPLAY 0.872340 (-623 1600);
PAINT GREEN (-623 1600);
DISPLAY INVISIBLE (-623 1600);
FORCEADD TAP..1
R 2
(-625 1450);
FORCEPROP 3 LASTPIN (-575 1450) SIG_NAME M_A_CPU0_SB_DQ<16>
J 0
(-565 1460);
DISPLAY 0.659574 (-565 1460);
PAINT MONO (-565 1460);
DISPLAY INVISIBLE (-565 1460);
FORCEPROP 1 LASTPIN (-575 1450) BN 16
J 2
(-563 1458);
DISPLAY 0.680851 (-563 1458);
PAINT GREEN (-563 1458);
FORCEPROP 2 LAST CDS_LIB standard
J 0
(-625 1450);
DISPLAY INVISIBLE (-625 1450);
FORCEPROP 1 LAST BODY_TYPE PLUMBING
J 2
(-625 1500);
DISPLAY 0.872340 (-625 1500);
PAINT GREEN (-625 1500);
DISPLAY INVISIBLE (-625 1500);
FORCEPROP 1 LAST HDL_TAP TRUE
J 2
(-950 1325);
DISPLAY 0.872340 (-950 1325);
DISPLAY INVISIBLE (-950 1325);
FORCEPROP 1 LAST PATH I49
J 2
(-623 1450);
DISPLAY 0.872340 (-623 1450);
PAINT GREEN (-623 1450);
DISPLAY INVISIBLE (-623 1450);
FORCEADD TAP..1
R 2
(-625 3250);
FORCEPROP 3 LASTPIN (-575 3250) SIG_NAME M_A_CPU0_SA_DQ<12>
J 0
(-565 3260);
DISPLAY 0.659574 (-565 3260);
PAINT MONO (-565 3260);
DISPLAY INVISIBLE (-565 3260);
FORCEPROP 1 LASTPIN (-575 3250) BN 12
J 2
(-563 3258);
DISPLAY 0.680851 (-563 3258);
PAINT GREEN (-563 3258);
FORCEPROP 2 LAST CDS_LIB standard
J 0
(-625 3250);
DISPLAY INVISIBLE (-625 3250);
FORCEPROP 1 LAST BODY_TYPE PLUMBING
J 2
(-625 3300);
DISPLAY 0.872340 (-625 3300);
PAINT GREEN (-625 3300);
DISPLAY INVISIBLE (-625 3300);
FORCEPROP 1 LAST HDL_TAP TRUE
J 2
(-950 3125);
DISPLAY 0.872340 (-950 3125);
DISPLAY INVISIBLE (-950 3125);
FORCEPROP 1 LAST PATH I5
J 2
(-623 3250);
DISPLAY 0.872340 (-623 3250);
PAINT GREEN (-623 3250);
DISPLAY INVISIBLE (-623 3250);
FORCEADD TAP..1
R 2
(-625 1500);
FORCEPROP 3 LASTPIN (-575 1500) SIG_NAME M_A_CPU0_SB_DQ<17>
J 0
(-565 1510);
DISPLAY 0.659574 (-565 1510);
PAINT MONO (-565 1510);
DISPLAY INVISIBLE (-565 1510);
FORCEPROP 1 LASTPIN (-575 1500) BN 17
J 2
(-563 1508);
DISPLAY 0.680851 (-563 1508);
PAINT GREEN (-563 1508);
FORCEPROP 2 LAST CDS_LIB standard
J 0
(-625 1500);
DISPLAY INVISIBLE (-625 1500);
FORCEPROP 1 LAST BODY_TYPE PLUMBING
J 2
(-625 1550);
DISPLAY 0.872340 (-625 1550);
PAINT GREEN (-625 1550);
DISPLAY INVISIBLE (-625 1550);
FORCEPROP 1 LAST HDL_TAP TRUE
J 2
(-950 1375);
DISPLAY 0.872340 (-950 1375);
DISPLAY INVISIBLE (-950 1375);
FORCEPROP 1 LAST PATH I50
J 2
(-623 1500);
DISPLAY 0.872340 (-623 1500);
PAINT GREEN (-623 1500);
DISPLAY INVISIBLE (-623 1500);
FORCEADD TAP..1
R 2
(-625 1550);
FORCEPROP 3 LASTPIN (-575 1550) SIG_NAME M_A_CPU0_SB_DQ<18>
J 0
(-565 1560);
DISPLAY 0.659574 (-565 1560);
PAINT MONO (-565 1560);
DISPLAY INVISIBLE (-565 1560);
FORCEPROP 1 LASTPIN (-575 1550) BN 18
J 2
(-563 1558);
DISPLAY 0.680851 (-563 1558);
PAINT GREEN (-563 1558);
FORCEPROP 2 LAST CDS_LIB standard
J 0
(-625 1550);
DISPLAY INVISIBLE (-625 1550);
FORCEPROP 1 LAST BODY_TYPE PLUMBING
J 2
(-625 1600);
DISPLAY 0.872340 (-625 1600);
PAINT GREEN (-625 1600);
DISPLAY INVISIBLE (-625 1600);
FORCEPROP 1 LAST HDL_TAP TRUE
J 2
(-950 1425);
DISPLAY 0.872340 (-950 1425);
DISPLAY INVISIBLE (-950 1425);
FORCEPROP 1 LAST PATH I51
J 2
(-623 1550);
DISPLAY 0.872340 (-623 1550);
PAINT GREEN (-623 1550);
DISPLAY INVISIBLE (-623 1550);
FORCEADD TAP..1
R 2
(-625 1400);
FORCEPROP 3 LASTPIN (-575 1400) SIG_NAME M_A_CPU0_SB_DQ<15>
J 0
(-565 1410);
DISPLAY 0.659574 (-565 1410);
PAINT MONO (-565 1410);
DISPLAY INVISIBLE (-565 1410);
FORCEPROP 1 LASTPIN (-575 1400) BN 15
J 2
(-563 1408);
DISPLAY 0.680851 (-563 1408);
PAINT GREEN (-563 1408);
FORCEPROP 2 LAST CDS_LIB standard
J 0
(-625 1400);
DISPLAY INVISIBLE (-625 1400);
FORCEPROP 1 LAST BODY_TYPE PLUMBING
J 2
(-625 1450);
DISPLAY 0.872340 (-625 1450);
PAINT GREEN (-625 1450);
DISPLAY INVISIBLE (-625 1450);
FORCEPROP 1 LAST HDL_TAP TRUE
J 2
(-950 1275);
DISPLAY 0.872340 (-950 1275);
DISPLAY INVISIBLE (-950 1275);
FORCEPROP 1 LAST PATH I52
J 2
(-623 1400);
DISPLAY 0.872340 (-623 1400);
PAINT GREEN (-623 1400);
DISPLAY INVISIBLE (-623 1400);
FORCEADD TAP..1
R 2
(-625 1350);
FORCEPROP 3 LASTPIN (-575 1350) SIG_NAME M_A_CPU0_SB_DQ<14>
J 0
(-565 1360);
DISPLAY 0.659574 (-565 1360);
PAINT MONO (-565 1360);
DISPLAY INVISIBLE (-565 1360);
FORCEPROP 1 LASTPIN (-575 1350) BN 14
J 2
(-563 1358);
DISPLAY 0.680851 (-563 1358);
PAINT GREEN (-563 1358);
FORCEPROP 2 LAST CDS_LIB standard
J 0
(-625 1350);
DISPLAY INVISIBLE (-625 1350);
FORCEPROP 1 LAST BODY_TYPE PLUMBING
J 2
(-625 1400);
DISPLAY 0.872340 (-625 1400);
PAINT GREEN (-625 1400);
DISPLAY INVISIBLE (-625 1400);
FORCEPROP 1 LAST HDL_TAP TRUE
J 2
(-950 1225);
DISPLAY 0.872340 (-950 1225);
DISPLAY INVISIBLE (-950 1225);
FORCEPROP 1 LAST PATH I53
J 2
(-623 1350);
DISPLAY 0.872340 (-623 1350);
PAINT GREEN (-623 1350);
DISPLAY INVISIBLE (-623 1350);
FORCEADD TAP..1
R 2
(-625 1250);
FORCEPROP 3 LASTPIN (-575 1250) SIG_NAME M_A_CPU0_SB_DQ<12>
J 0
(-565 1260);
DISPLAY 0.659574 (-565 1260);
PAINT MONO (-565 1260);
DISPLAY INVISIBLE (-565 1260);
FORCEPROP 1 LASTPIN (-575 1250) BN 12
J 2
(-563 1258);
DISPLAY 0.680851 (-563 1258);
PAINT GREEN (-563 1258);
FORCEPROP 2 LAST CDS_LIB standard
J 0
(-625 1250);
DISPLAY INVISIBLE (-625 1250);
FORCEPROP 1 LAST BODY_TYPE PLUMBING
J 2
(-625 1300);
DISPLAY 0.872340 (-625 1300);
PAINT GREEN (-625 1300);
DISPLAY INVISIBLE (-625 1300);
FORCEPROP 1 LAST HDL_TAP TRUE
J 2
(-950 1125);
DISPLAY 0.872340 (-950 1125);
DISPLAY INVISIBLE (-950 1125);
FORCEPROP 1 LAST PATH I54
J 2
(-623 1250);
DISPLAY 0.872340 (-623 1250);
PAINT GREEN (-623 1250);
DISPLAY INVISIBLE (-623 1250);
FORCEADD TAP..1
R 2
(-625 1200);
FORCEPROP 3 LASTPIN (-575 1200) SIG_NAME M_A_CPU0_SB_DQ<11>
J 0
(-565 1210);
DISPLAY 0.659574 (-565 1210);
PAINT MONO (-565 1210);
DISPLAY INVISIBLE (-565 1210);
FORCEPROP 1 LASTPIN (-575 1200) BN 11
J 2
(-563 1208);
DISPLAY 0.680851 (-563 1208);
PAINT GREEN (-563 1208);
FORCEPROP 2 LAST CDS_LIB standard
J 0
(-625 1200);
DISPLAY INVISIBLE (-625 1200);
FORCEPROP 1 LAST BODY_TYPE PLUMBING
J 2
(-625 1250);
DISPLAY 0.872340 (-625 1250);
PAINT GREEN (-625 1250);
DISPLAY INVISIBLE (-625 1250);
FORCEPROP 1 LAST HDL_TAP TRUE
J 2
(-950 1075);
DISPLAY 0.872340 (-950 1075);
DISPLAY INVISIBLE (-950 1075);
FORCEPROP 1 LAST PATH I55
J 2
(-623 1200);
DISPLAY 0.872340 (-623 1200);
PAINT GREEN (-623 1200);
DISPLAY INVISIBLE (-623 1200);
FORCEADD TAP..1
R 2
(-625 1300);
FORCEPROP 3 LASTPIN (-575 1300) SIG_NAME M_A_CPU0_SB_DQ<13>
J 0
(-565 1310);
DISPLAY 0.659574 (-565 1310);
PAINT MONO (-565 1310);
DISPLAY INVISIBLE (-565 1310);
FORCEPROP 1 LASTPIN (-575 1300) BN 13
J 2
(-563 1308);
DISPLAY 0.680851 (-563 1308);
PAINT GREEN (-563 1308);
FORCEPROP 2 LAST CDS_LIB standard
J 0
(-625 1300);
DISPLAY INVISIBLE (-625 1300);
FORCEPROP 1 LAST BODY_TYPE PLUMBING
J 2
(-625 1350);
DISPLAY 0.872340 (-625 1350);
PAINT GREEN (-625 1350);
DISPLAY INVISIBLE (-625 1350);
FORCEPROP 1 LAST HDL_TAP TRUE
J 2
(-950 1175);
DISPLAY 0.872340 (-950 1175);
DISPLAY INVISIBLE (-950 1175);
FORCEPROP 1 LAST PATH I56
J 2
(-623 1300);
DISPLAY 0.872340 (-623 1300);
PAINT GREEN (-623 1300);
DISPLAY INVISIBLE (-623 1300);
FORCEADD TAP..1
R 2
(-625 1100);
FORCEPROP 3 LASTPIN (-575 1100) SIG_NAME M_A_CPU0_SB_DQ<9>
J 0
(-565 1110);
DISPLAY 0.659574 (-565 1110);
PAINT MONO (-565 1110);
DISPLAY INVISIBLE (-565 1110);
FORCEPROP 1 LASTPIN (-575 1100) BN 9
J 2
(-563 1108);
DISPLAY 0.680851 (-563 1108);
PAINT GREEN (-563 1108);
FORCEPROP 2 LAST CDS_LIB standard
J 0
(-625 1100);
DISPLAY INVISIBLE (-625 1100);
FORCEPROP 1 LAST BODY_TYPE PLUMBING
J 2
(-625 1150);
DISPLAY 0.872340 (-625 1150);
PAINT GREEN (-625 1150);
DISPLAY INVISIBLE (-625 1150);
FORCEPROP 1 LAST HDL_TAP TRUE
J 2
(-950 975);
DISPLAY 0.872340 (-950 975);
DISPLAY INVISIBLE (-950 975);
FORCEPROP 1 LAST PATH I57
J 2
(-623 1100);
DISPLAY 0.872340 (-623 1100);
PAINT GREEN (-623 1100);
DISPLAY INVISIBLE (-623 1100);
FORCEADD TAP..1
R 2
(-625 1150);
FORCEPROP 3 LASTPIN (-575 1150) SIG_NAME M_A_CPU0_SB_DQ<10>
J 0
(-565 1160);
DISPLAY 0.659574 (-565 1160);
PAINT MONO (-565 1160);
DISPLAY INVISIBLE (-565 1160);
FORCEPROP 1 LASTPIN (-575 1150) BN 10
J 2
(-563 1158);
DISPLAY 0.680851 (-563 1158);
PAINT GREEN (-563 1158);
FORCEPROP 2 LAST CDS_LIB standard
J 0
(-625 1150);
DISPLAY INVISIBLE (-625 1150);
FORCEPROP 1 LAST BODY_TYPE PLUMBING
J 2
(-625 1200);
DISPLAY 0.872340 (-625 1200);
PAINT GREEN (-625 1200);
DISPLAY INVISIBLE (-625 1200);
FORCEPROP 1 LAST HDL_TAP TRUE
J 2
(-950 1025);
DISPLAY 0.872340 (-950 1025);
DISPLAY INVISIBLE (-950 1025);
FORCEPROP 1 LAST PATH I58
J 2
(-623 1150);
DISPLAY 0.872340 (-623 1150);
PAINT GREEN (-623 1150);
DISPLAY INVISIBLE (-623 1150);
FORCEADD TAP..1
R 2
(-625 1050);
FORCEPROP 3 LASTPIN (-575 1050) SIG_NAME M_A_CPU0_SB_DQ<8>
J 0
(-565 1060);
DISPLAY 0.659574 (-565 1060);
PAINT MONO (-565 1060);
DISPLAY INVISIBLE (-565 1060);
FORCEPROP 1 LASTPIN (-575 1050) BN 8
J 2
(-563 1058);
DISPLAY 0.680851 (-563 1058);
PAINT GREEN (-563 1058);
FORCEPROP 2 LAST CDS_LIB standard
J 0
(-625 1050);
DISPLAY INVISIBLE (-625 1050);
FORCEPROP 1 LAST BODY_TYPE PLUMBING
J 2
(-625 1100);
DISPLAY 0.872340 (-625 1100);
PAINT GREEN (-625 1100);
DISPLAY INVISIBLE (-625 1100);
FORCEPROP 1 LAST HDL_TAP TRUE
J 2
(-950 925);
DISPLAY 0.872340 (-950 925);
DISPLAY INVISIBLE (-950 925);
FORCEPROP 1 LAST PATH I59
J 2
(-623 1050);
DISPLAY 0.872340 (-623 1050);
PAINT GREEN (-623 1050);
DISPLAY INVISIBLE (-623 1050);
FORCEADD TAP..1
R 2
(-625 3300);
FORCEPROP 3 LASTPIN (-575 3300) SIG_NAME M_A_CPU0_SA_DQ<13>
J 0
(-565 3310);
DISPLAY 0.659574 (-565 3310);
PAINT MONO (-565 3310);
DISPLAY INVISIBLE (-565 3310);
FORCEPROP 1 LASTPIN (-575 3300) BN 13
J 2
(-563 3308);
DISPLAY 0.680851 (-563 3308);
PAINT GREEN (-563 3308);
FORCEPROP 2 LAST CDS_LIB standard
J 0
(-625 3300);
DISPLAY INVISIBLE (-625 3300);
FORCEPROP 1 LAST BODY_TYPE PLUMBING
J 2
(-625 3350);
DISPLAY 0.872340 (-625 3350);
PAINT GREEN (-625 3350);
DISPLAY INVISIBLE (-625 3350);
FORCEPROP 1 LAST HDL_TAP TRUE
J 2
(-950 3175);
DISPLAY 0.872340 (-950 3175);
DISPLAY INVISIBLE (-950 3175);
FORCEPROP 1 LAST PATH I6
J 2
(-623 3300);
DISPLAY 0.872340 (-623 3300);
PAINT GREEN (-623 3300);
DISPLAY INVISIBLE (-623 3300);
FORCEADD TAP..1
R 2
(-625 950);
FORCEPROP 3 LASTPIN (-575 950) SIG_NAME M_A_CPU0_SB_DQ<6>
J 0
(-565 960);
DISPLAY 0.659574 (-565 960);
PAINT MONO (-565 960);
DISPLAY INVISIBLE (-565 960);
FORCEPROP 1 LASTPIN (-575 950) BN 6
J 2
(-563 958);
DISPLAY 0.680851 (-563 958);
PAINT GREEN (-563 958);
FORCEPROP 2 LAST CDS_LIB standard
J 0
(-625 950);
DISPLAY INVISIBLE (-625 950);
FORCEPROP 1 LAST BODY_TYPE PLUMBING
J 2
(-625 1000);
DISPLAY 0.872340 (-625 1000);
PAINT GREEN (-625 1000);
DISPLAY INVISIBLE (-625 1000);
FORCEPROP 1 LAST HDL_TAP TRUE
J 2
(-950 825);
DISPLAY 0.872340 (-950 825);
DISPLAY INVISIBLE (-950 825);
FORCEPROP 1 LAST PATH I60
J 2
(-623 950);
DISPLAY 0.872340 (-623 950);
PAINT GREEN (-623 950);
DISPLAY INVISIBLE (-623 950);
FORCEADD TAP..1
R 2
(-625 1000);
FORCEPROP 3 LASTPIN (-575 1000) SIG_NAME M_A_CPU0_SB_DQ<7>
J 0
(-565 1010);
DISPLAY 0.659574 (-565 1010);
PAINT MONO (-565 1010);
DISPLAY INVISIBLE (-565 1010);
FORCEPROP 1 LASTPIN (-575 1000) BN 7
J 2
(-563 1008);
DISPLAY 0.680851 (-563 1008);
PAINT GREEN (-563 1008);
FORCEPROP 2 LAST CDS_LIB standard
J 0
(-625 1000);
DISPLAY INVISIBLE (-625 1000);
FORCEPROP 1 LAST BODY_TYPE PLUMBING
J 2
(-625 1050);
DISPLAY 0.872340 (-625 1050);
PAINT GREEN (-625 1050);
DISPLAY INVISIBLE (-625 1050);
FORCEPROP 1 LAST HDL_TAP TRUE
J 2
(-950 875);
DISPLAY 0.872340 (-950 875);
DISPLAY INVISIBLE (-950 875);
FORCEPROP 1 LAST PATH I61
J 2
(-623 1000);
DISPLAY 0.872340 (-623 1000);
PAINT GREEN (-623 1000);
DISPLAY INVISIBLE (-623 1000);
FORCEADD TAP..1
R 2
(-625 900);
FORCEPROP 3 LASTPIN (-575 900) SIG_NAME M_A_CPU0_SB_DQ<5>
J 0
(-565 910);
DISPLAY 0.659574 (-565 910);
PAINT MONO (-565 910);
DISPLAY INVISIBLE (-565 910);
FORCEPROP 1 LASTPIN (-575 900) BN 5
J 2
(-563 908);
DISPLAY 0.680851 (-563 908);
PAINT GREEN (-563 908);
FORCEPROP 2 LAST CDS_LIB standard
J 0
(-625 900);
DISPLAY INVISIBLE (-625 900);
FORCEPROP 1 LAST BODY_TYPE PLUMBING
J 2
(-625 950);
DISPLAY 0.872340 (-625 950);
PAINT GREEN (-625 950);
DISPLAY INVISIBLE (-625 950);
FORCEPROP 1 LAST HDL_TAP TRUE
J 2
(-950 775);
DISPLAY 0.872340 (-950 775);
DISPLAY INVISIBLE (-950 775);
FORCEPROP 1 LAST PATH I62
J 2
(-623 900);
DISPLAY 0.872340 (-623 900);
PAINT GREEN (-623 900);
DISPLAY INVISIBLE (-623 900);
FORCEADD TAP..1
R 2
(-625 850);
FORCEPROP 3 LASTPIN (-575 850) SIG_NAME M_A_CPU0_SB_DQ<4>
J 0
(-565 860);
DISPLAY 0.659574 (-565 860);
PAINT MONO (-565 860);
DISPLAY INVISIBLE (-565 860);
FORCEPROP 1 LASTPIN (-575 850) BN 4
J 2
(-563 858);
DISPLAY 0.680851 (-563 858);
PAINT GREEN (-563 858);
FORCEPROP 2 LAST CDS_LIB standard
J 0
(-625 850);
DISPLAY INVISIBLE (-625 850);
FORCEPROP 1 LAST BODY_TYPE PLUMBING
J 2
(-625 900);
DISPLAY 0.872340 (-625 900);
PAINT GREEN (-625 900);
DISPLAY INVISIBLE (-625 900);
FORCEPROP 1 LAST HDL_TAP TRUE
J 2
(-950 725);
DISPLAY 0.872340 (-950 725);
DISPLAY INVISIBLE (-950 725);
FORCEPROP 1 LAST PATH I63
J 2
(-623 850);
DISPLAY 0.872340 (-623 850);
PAINT GREEN (-623 850);
DISPLAY INVISIBLE (-623 850);
FORCEADD TAP..1
R 2
(-625 800);
FORCEPROP 3 LASTPIN (-575 800) SIG_NAME M_A_CPU0_SB_DQ<3>
J 0
(-565 810);
DISPLAY 0.659574 (-565 810);
PAINT MONO (-565 810);
DISPLAY INVISIBLE (-565 810);
FORCEPROP 1 LASTPIN (-575 800) BN 3
J 2
(-563 808);
DISPLAY 0.680851 (-563 808);
PAINT GREEN (-563 808);
FORCEPROP 2 LAST CDS_LIB standard
J 0
(-625 800);
DISPLAY INVISIBLE (-625 800);
FORCEPROP 1 LAST BODY_TYPE PLUMBING
J 2
(-625 850);
DISPLAY 0.872340 (-625 850);
PAINT GREEN (-625 850);
DISPLAY INVISIBLE (-625 850);
FORCEPROP 1 LAST HDL_TAP TRUE
J 2
(-950 675);
DISPLAY 0.872340 (-950 675);
DISPLAY INVISIBLE (-950 675);
FORCEPROP 1 LAST PATH I64
J 2
(-623 800);
DISPLAY 0.872340 (-623 800);
PAINT GREEN (-623 800);
DISPLAY INVISIBLE (-623 800);
FORCEADD TAP..1
R 2
(-625 650);
FORCEPROP 3 LASTPIN (-575 650) SIG_NAME M_A_CPU0_SB_DQ<0>
J 0
(-565 660);
DISPLAY 0.659574 (-565 660);
PAINT MONO (-565 660);
DISPLAY INVISIBLE (-565 660);
FORCEPROP 1 LASTPIN (-575 650) BN 0
J 2
(-563 658);
DISPLAY 0.680851 (-563 658);
PAINT GREEN (-563 658);
FORCEPROP 2 LAST CDS_LIB standard
J 0
(-625 650);
DISPLAY INVISIBLE (-625 650);
FORCEPROP 1 LAST BODY_TYPE PLUMBING
J 2
(-625 700);
DISPLAY 0.872340 (-625 700);
PAINT GREEN (-625 700);
DISPLAY INVISIBLE (-625 700);
FORCEPROP 1 LAST HDL_TAP TRUE
J 2
(-950 525);
DISPLAY 0.872340 (-950 525);
DISPLAY INVISIBLE (-950 525);
FORCEPROP 1 LAST PATH I65
J 2
(-623 650);
DISPLAY 0.872340 (-623 650);
PAINT GREEN (-623 650);
DISPLAY INVISIBLE (-623 650);
FORCEADD TAP..1
R 2
(-625 700);
FORCEPROP 3 LASTPIN (-575 700) SIG_NAME M_A_CPU0_SB_DQ<1>
J 0
(-565 710);
DISPLAY 0.659574 (-565 710);
PAINT MONO (-565 710);
DISPLAY INVISIBLE (-565 710);
FORCEPROP 1 LASTPIN (-575 700) BN 1
J 2
(-563 708);
DISPLAY 0.680851 (-563 708);
PAINT GREEN (-563 708);
FORCEPROP 2 LAST CDS_LIB standard
J 0
(-625 700);
DISPLAY INVISIBLE (-625 700);
FORCEPROP 1 LAST BODY_TYPE PLUMBING
J 2
(-625 750);
DISPLAY 0.872340 (-625 750);
PAINT GREEN (-625 750);
DISPLAY INVISIBLE (-625 750);
FORCEPROP 1 LAST HDL_TAP TRUE
J 2
(-950 575);
DISPLAY 0.872340 (-950 575);
DISPLAY INVISIBLE (-950 575);
FORCEPROP 1 LAST PATH I66
J 2
(-623 700);
DISPLAY 0.872340 (-623 700);
PAINT GREEN (-623 700);
DISPLAY INVISIBLE (-623 700);
FORCEADD TAP..1
R 2
(-625 750);
FORCEPROP 3 LASTPIN (-575 750) SIG_NAME M_A_CPU0_SB_DQ<2>
J 0
(-565 760);
DISPLAY 0.659574 (-565 760);
PAINT MONO (-565 760);
DISPLAY INVISIBLE (-565 760);
FORCEPROP 1 LASTPIN (-575 750) BN 2
J 2
(-563 758);
DISPLAY 0.680851 (-563 758);
PAINT GREEN (-563 758);
FORCEPROP 2 LAST CDS_LIB standard
J 0
(-625 750);
DISPLAY INVISIBLE (-625 750);
FORCEPROP 1 LAST BODY_TYPE PLUMBING
J 2
(-625 800);
DISPLAY 0.872340 (-625 800);
PAINT GREEN (-625 800);
DISPLAY INVISIBLE (-625 800);
FORCEPROP 1 LAST HDL_TAP TRUE
J 2
(-950 625);
DISPLAY 0.872340 (-950 625);
DISPLAY INVISIBLE (-950 625);
FORCEPROP 1 LAST PATH I67
J 2
(-623 750);
DISPLAY 0.872340 (-623 750);
PAINT GREEN (-623 750);
DISPLAY INVISIBLE (-623 750);
FORCEADD TAP..1
R 2
(-625 2350);
FORCEPROP 3 LASTPIN (-575 2350) SIG_NAME M_A_CPU0_SA_CB<2>
J 0
(-565 2360);
DISPLAY 0.659574 (-565 2360);
PAINT MONO (-565 2360);
DISPLAY INVISIBLE (-565 2360);
FORCEPROP 1 LASTPIN (-575 2350) BN 2
J 2
(-563 2358);
DISPLAY 0.680851 (-563 2358);
PAINT GREEN (-563 2358);
FORCEPROP 2 LAST CDS_LIB standard
J 0
(-625 2350);
DISPLAY INVISIBLE (-625 2350);
FORCEPROP 1 LAST BODY_TYPE PLUMBING
J 2
(-625 2400);
DISPLAY 0.872340 (-625 2400);
PAINT GREEN (-625 2400);
DISPLAY INVISIBLE (-625 2400);
FORCEPROP 1 LAST HDL_TAP TRUE
J 2
(-950 2225);
DISPLAY 0.872340 (-950 2225);
DISPLAY INVISIBLE (-950 2225);
FORCEPROP 1 LAST PATH I68
J 2
(-623 2350);
DISPLAY 0.872340 (-623 2350);
PAINT GREEN (-623 2350);
DISPLAY INVISIBLE (-623 2350);
FORCEADD TAP..1
R 2
(-625 2250);
FORCEPROP 3 LASTPIN (-575 2250) SIG_NAME M_A_CPU0_SA_CB<0>
J 0
(-565 2260);
DISPLAY 0.659574 (-565 2260);
PAINT MONO (-565 2260);
DISPLAY INVISIBLE (-565 2260);
FORCEPROP 1 LASTPIN (-575 2250) BN 0
J 2
(-563 2258);
DISPLAY 0.680851 (-563 2258);
PAINT GREEN (-563 2258);
FORCEPROP 2 LAST CDS_LIB standard
J 0
(-625 2250);
DISPLAY INVISIBLE (-625 2250);
FORCEPROP 1 LAST BODY_TYPE PLUMBING
J 2
(-625 2300);
DISPLAY 0.872340 (-625 2300);
PAINT GREEN (-625 2300);
DISPLAY INVISIBLE (-625 2300);
FORCEPROP 1 LAST HDL_TAP TRUE
J 2
(-950 2125);
DISPLAY 0.872340 (-950 2125);
DISPLAY INVISIBLE (-950 2125);
FORCEPROP 1 LAST PATH I69
J 2
(-623 2250);
DISPLAY 0.872340 (-623 2250);
PAINT GREEN (-623 2250);
DISPLAY INVISIBLE (-623 2250);
FORCEADD TAP..1
R 2
(-625 3350);
FORCEPROP 3 LASTPIN (-575 3350) SIG_NAME M_A_CPU0_SA_DQ<14>
J 0
(-565 3360);
DISPLAY 0.659574 (-565 3360);
PAINT MONO (-565 3360);
DISPLAY INVISIBLE (-565 3360);
FORCEPROP 1 LASTPIN (-575 3350) BN 14
J 2
(-563 3358);
DISPLAY 0.680851 (-563 3358);
PAINT GREEN (-563 3358);
FORCEPROP 2 LAST CDS_LIB standard
J 0
(-625 3350);
DISPLAY INVISIBLE (-625 3350);
FORCEPROP 1 LAST BODY_TYPE PLUMBING
J 2
(-625 3400);
DISPLAY 0.872340 (-625 3400);
PAINT GREEN (-625 3400);
DISPLAY INVISIBLE (-625 3400);
FORCEPROP 1 LAST HDL_TAP TRUE
J 2
(-950 3225);
DISPLAY 0.872340 (-950 3225);
DISPLAY INVISIBLE (-950 3225);
FORCEPROP 1 LAST PATH I7
J 2
(-623 3350);
DISPLAY 0.872340 (-623 3350);
PAINT GREEN (-623 3350);
DISPLAY INVISIBLE (-623 3350);
FORCEADD TAP..1
R 2
(-625 2450);
FORCEPROP 3 LASTPIN (-575 2450) SIG_NAME M_A_CPU0_SA_CB<4>
J 0
(-565 2460);
DISPLAY 0.659574 (-565 2460);
PAINT MONO (-565 2460);
DISPLAY INVISIBLE (-565 2460);
FORCEPROP 1 LASTPIN (-575 2450) BN 4
J 2
(-563 2458);
DISPLAY 0.680851 (-563 2458);
PAINT GREEN (-563 2458);
FORCEPROP 2 LAST CDS_LIB standard
J 0
(-625 2450);
DISPLAY INVISIBLE (-625 2450);
FORCEPROP 1 LAST BODY_TYPE PLUMBING
J 2
(-625 2500);
DISPLAY 0.872340 (-625 2500);
PAINT GREEN (-625 2500);
DISPLAY INVISIBLE (-625 2500);
FORCEPROP 1 LAST HDL_TAP TRUE
J 2
(-950 2325);
DISPLAY 0.872340 (-950 2325);
DISPLAY INVISIBLE (-950 2325);
FORCEPROP 1 LAST PATH I70
J 2
(-623 2450);
DISPLAY 0.872340 (-623 2450);
PAINT GREEN (-623 2450);
DISPLAY INVISIBLE (-623 2450);
FORCEADD TAP..1
R 2
(-625 2600);
FORCEPROP 3 LASTPIN (-575 2600) SIG_NAME M_A_CPU0_SA_CB<7>
J 0
(-565 2610);
DISPLAY 0.659574 (-565 2610);
PAINT MONO (-565 2610);
DISPLAY INVISIBLE (-565 2610);
FORCEPROP 1 LASTPIN (-575 2600) BN 7
J 2
(-563 2608);
DISPLAY 0.680851 (-563 2608);
PAINT GREEN (-563 2608);
FORCEPROP 2 LAST CDS_LIB standard
J 0
(-625 2600);
DISPLAY INVISIBLE (-625 2600);
FORCEPROP 1 LAST BODY_TYPE PLUMBING
J 2
(-625 2650);
DISPLAY 0.872340 (-625 2650);
PAINT GREEN (-625 2650);
DISPLAY INVISIBLE (-625 2650);
FORCEPROP 1 LAST HDL_TAP TRUE
J 2
(-950 2475);
DISPLAY 0.872340 (-950 2475);
DISPLAY INVISIBLE (-950 2475);
FORCEPROP 1 LAST PATH I71
J 2
(-623 2600);
DISPLAY 0.872340 (-623 2600);
PAINT GREEN (-623 2600);
DISPLAY INVISIBLE (-623 2600);
FORCEADD TAP..1
R 2
(-625 2550);
FORCEPROP 3 LASTPIN (-575 2550) SIG_NAME M_A_CPU0_SA_CB<6>
J 0
(-565 2560);
DISPLAY 0.659574 (-565 2560);
PAINT MONO (-565 2560);
DISPLAY INVISIBLE (-565 2560);
FORCEPROP 1 LASTPIN (-575 2550) BN 6
J 2
(-563 2558);
DISPLAY 0.680851 (-563 2558);
PAINT GREEN (-563 2558);
FORCEPROP 2 LAST CDS_LIB standard
J 0
(-625 2550);
DISPLAY INVISIBLE (-625 2550);
FORCEPROP 1 LAST BODY_TYPE PLUMBING
J 2
(-625 2600);
DISPLAY 0.872340 (-625 2600);
PAINT GREEN (-625 2600);
DISPLAY INVISIBLE (-625 2600);
FORCEPROP 1 LAST HDL_TAP TRUE
J 2
(-950 2425);
DISPLAY 0.872340 (-950 2425);
DISPLAY INVISIBLE (-950 2425);
FORCEPROP 1 LAST PATH I72
J 2
(-623 2550);
DISPLAY 0.872340 (-623 2550);
PAINT GREEN (-623 2550);
DISPLAY INVISIBLE (-623 2550);
FORCEADD TAP..1
R 2
(-625 2500);
FORCEPROP 3 LASTPIN (-575 2500) SIG_NAME M_A_CPU0_SA_CB<5>
J 0
(-565 2510);
DISPLAY 0.659574 (-565 2510);
PAINT MONO (-565 2510);
DISPLAY INVISIBLE (-565 2510);
FORCEPROP 1 LASTPIN (-575 2500) BN 5
J 2
(-563 2508);
DISPLAY 0.680851 (-563 2508);
PAINT GREEN (-563 2508);
FORCEPROP 2 LAST CDS_LIB standard
J 0
(-625 2500);
DISPLAY INVISIBLE (-625 2500);
FORCEPROP 1 LAST BODY_TYPE PLUMBING
J 2
(-625 2550);
DISPLAY 0.872340 (-625 2550);
PAINT GREEN (-625 2550);
DISPLAY INVISIBLE (-625 2550);
FORCEPROP 1 LAST HDL_TAP TRUE
J 2
(-950 2375);
DISPLAY 0.872340 (-950 2375);
DISPLAY INVISIBLE (-950 2375);
FORCEPROP 1 LAST PATH I73
J 2
(-623 2500);
DISPLAY 0.872340 (-623 2500);
PAINT GREEN (-623 2500);
DISPLAY INVISIBLE (-623 2500);
FORCEADD OFFPAGE..3
R 2
(-1650 2625);
FORCEPROP 2 LAST $XR1 83 
J 0
(-2019 2625);
DISPLAY 0.638298 (-2019 2625);
PAINT MONO (-2019 2625);
FORCEPROP 2 LAST $XR0 82 
J 0
(-1929 2625);
DISPLAY 0.638298 (-1929 2625);
PAINT MONO (-1929 2625);
FORCEPROP 2 LAST CDS_LIB standard
J 0
(-1650 2625);
DISPLAY INVISIBLE (-1650 2625);
FORCEPROP 1 LAST OFFPAGE TRUE
J 2
(-1975 2500);
DISPLAY 0.872340 (-1975 2500);
DISPLAY INVISIBLE (-1975 2500);
FORCEPROP 1 LAST COMMENT_BODY TRUE
J 2
(-1600 2525);
DISPLAY 0.872340 (-1600 2525);
PAINT GREEN (-1600 2525);
DISPLAY INVISIBLE (-1600 2525);
FORCEPROP 2 LAST PATH I74
J 0
(-1975 2675);
DISPLAY 1.021277 (-1975 2675);
DISPLAY INVISIBLE (-1975 2675);
FORCEADD TAP..1
R 2
(-625 2400);
FORCEPROP 3 LASTPIN (-575 2400) SIG_NAME M_A_CPU0_SA_CB<3>
J 0
(-565 2410);
DISPLAY 0.659574 (-565 2410);
PAINT MONO (-565 2410);
DISPLAY INVISIBLE (-565 2410);
FORCEPROP 1 LASTPIN (-575 2400) BN 3
J 2
(-563 2408);
DISPLAY 0.680851 (-563 2408);
PAINT GREEN (-563 2408);
FORCEPROP 2 LAST CDS_LIB standard
J 0
(-625 2400);
DISPLAY INVISIBLE (-625 2400);
FORCEPROP 1 LAST BODY_TYPE PLUMBING
J 2
(-625 2450);
DISPLAY 0.872340 (-625 2450);
PAINT GREEN (-625 2450);
DISPLAY INVISIBLE (-625 2450);
FORCEPROP 1 LAST HDL_TAP TRUE
J 2
(-950 2275);
DISPLAY 0.872340 (-950 2275);
DISPLAY INVISIBLE (-950 2275);
FORCEPROP 1 LAST PATH I75
J 2
(-623 2400);
DISPLAY 0.872340 (-623 2400);
PAINT GREEN (-623 2400);
DISPLAY INVISIBLE (-623 2400);
FORCEADD TAP..1
R 2
(-625 2300);
FORCEPROP 3 LASTPIN (-575 2300) SIG_NAME M_A_CPU0_SA_CB<1>
J 0
(-565 2310);
DISPLAY 0.659574 (-565 2310);
PAINT MONO (-565 2310);
DISPLAY INVISIBLE (-565 2310);
FORCEPROP 1 LASTPIN (-575 2300) BN 1
J 2
(-563 2308);
DISPLAY 0.680851 (-563 2308);
PAINT GREEN (-563 2308);
FORCEPROP 2 LAST CDS_LIB standard
J 0
(-625 2300);
DISPLAY INVISIBLE (-625 2300);
FORCEPROP 1 LAST BODY_TYPE PLUMBING
J 2
(-625 2350);
DISPLAY 0.872340 (-625 2350);
PAINT GREEN (-625 2350);
DISPLAY INVISIBLE (-625 2350);
FORCEPROP 1 LAST HDL_TAP TRUE
J 2
(-950 2175);
DISPLAY 0.872340 (-950 2175);
DISPLAY INVISIBLE (-950 2175);
FORCEPROP 1 LAST PATH I76
J 2
(-623 2300);
DISPLAY 0.872340 (-623 2300);
PAINT GREEN (-623 2300);
DISPLAY INVISIBLE (-623 2300);
FORCEADD TAP..1
R 2
(-625 3400);
FORCEPROP 3 LASTPIN (-575 3400) SIG_NAME M_A_CPU0_SA_DQ<15>
J 0
(-565 3410);
DISPLAY 0.659574 (-565 3410);
PAINT MONO (-565 3410);
DISPLAY INVISIBLE (-565 3410);
FORCEPROP 1 LASTPIN (-575 3400) BN 15
J 2
(-563 3408);
DISPLAY 0.680851 (-563 3408);
PAINT GREEN (-563 3408);
FORCEPROP 2 LAST CDS_LIB standard
J 0
(-625 3400);
DISPLAY INVISIBLE (-625 3400);
FORCEPROP 1 LAST BODY_TYPE PLUMBING
J 2
(-625 3450);
DISPLAY 0.872340 (-625 3450);
PAINT GREEN (-625 3450);
DISPLAY INVISIBLE (-625 3450);
FORCEPROP 1 LAST HDL_TAP TRUE
J 2
(-950 3275);
DISPLAY 0.872340 (-950 3275);
DISPLAY INVISIBLE (-950 3275);
FORCEPROP 1 LAST PATH I8
J 2
(-623 3400);
DISPLAY 0.872340 (-623 3400);
PAINT GREEN (-623 3400);
DISPLAY INVISIBLE (-623 3400);
FORCEADD TAP..1
(2800 3750);
FORCEPROP 3 LASTPIN (2750 3750) SIG_NAME M_A_CPU0_SA_DQS_DP<0>
J 0
(2760 3760);
DISPLAY 0.659574 (2760 3760);
PAINT MONO (2760 3760);
DISPLAY INVISIBLE (2760 3760);
FORCEPROP 1 LASTPIN (2750 3750) BN 0
J 0
(2738 3758);
DISPLAY 0.680851 (2738 3758);
PAINT GREEN (2738 3758);
FORCEPROP 2 LAST CDS_LIB standard
J 0
(2800 3750);
DISPLAY INVISIBLE (2800 3750);
FORCEPROP 1 LAST BODY_TYPE PLUMBING
J 0
(2800 3800);
DISPLAY 0.872340 (2800 3800);
PAINT GREEN (2800 3800);
DISPLAY INVISIBLE (2800 3800);
FORCEPROP 1 LAST HDL_TAP TRUE
J 0
(3125 3625);
DISPLAY 0.872340 (3125 3625);
DISPLAY INVISIBLE (3125 3625);
FORCEPROP 1 LAST PATH I82
J 0
(2798 3750);
DISPLAY 0.872340 (2798 3750);
PAINT GREEN (2798 3750);
DISPLAY INVISIBLE (2798 3750);
FORCEADD TAP..1
(2800 3850);
FORCEPROP 3 LASTPIN (2750 3850) SIG_NAME M_A_CPU0_SA_DQS_DP<2>
J 0
(2760 3860);
DISPLAY 0.659574 (2760 3860);
PAINT MONO (2760 3860);
DISPLAY INVISIBLE (2760 3860);
FORCEPROP 1 LASTPIN (2750 3850) BN 2
J 0
(2738 3858);
DISPLAY 0.680851 (2738 3858);
PAINT GREEN (2738 3858);
FORCEPROP 2 LAST CDS_LIB standard
J 0
(2800 3850);
DISPLAY INVISIBLE (2800 3850);
FORCEPROP 1 LAST BODY_TYPE PLUMBING
J 0
(2800 3900);
DISPLAY 0.872340 (2800 3900);
PAINT GREEN (2800 3900);
DISPLAY INVISIBLE (2800 3900);
FORCEPROP 1 LAST HDL_TAP TRUE
J 0
(3125 3725);
DISPLAY 0.872340 (3125 3725);
DISPLAY INVISIBLE (3125 3725);
FORCEPROP 1 LAST PATH I84
J 0
(2798 3850);
DISPLAY 0.872340 (2798 3850);
PAINT GREEN (2798 3850);
DISPLAY INVISIBLE (2798 3850);
FORCEADD TAP..1
(2800 3800);
FORCEPROP 3 LASTPIN (2750 3800) SIG_NAME M_A_CPU0_SA_DQS_DP<1>
J 0
(2760 3810);
DISPLAY 0.659574 (2760 3810);
PAINT MONO (2760 3810);
DISPLAY INVISIBLE (2760 3810);
FORCEPROP 1 LASTPIN (2750 3800) BN 1
J 0
(2738 3808);
DISPLAY 0.680851 (2738 3808);
PAINT GREEN (2738 3808);
FORCEPROP 2 LAST CDS_LIB standard
J 0
(2800 3800);
DISPLAY INVISIBLE (2800 3800);
FORCEPROP 1 LAST BODY_TYPE PLUMBING
J 0
(2800 3850);
DISPLAY 0.872340 (2800 3850);
PAINT GREEN (2800 3850);
DISPLAY INVISIBLE (2800 3850);
FORCEPROP 1 LAST HDL_TAP TRUE
J 0
(3125 3675);
DISPLAY 0.872340 (3125 3675);
DISPLAY INVISIBLE (3125 3675);
FORCEPROP 1 LAST PATH I85
J 0
(2798 3800);
DISPLAY 0.872340 (2798 3800);
PAINT GREEN (2798 3800);
DISPLAY INVISIBLE (2798 3800);
FORCEADD TAP..1
(2800 3900);
FORCEPROP 3 LASTPIN (2750 3900) SIG_NAME M_A_CPU0_SA_DQS_DP<3>
J 0
(2760 3910);
DISPLAY 0.659574 (2760 3910);
PAINT MONO (2760 3910);
DISPLAY INVISIBLE (2760 3910);
FORCEPROP 1 LASTPIN (2750 3900) BN 3
J 0
(2738 3908);
DISPLAY 0.680851 (2738 3908);
PAINT GREEN (2738 3908);
FORCEPROP 2 LAST CDS_LIB standard
J 0
(2800 3900);
DISPLAY INVISIBLE (2800 3900);
FORCEPROP 1 LAST BODY_TYPE PLUMBING
J 0
(2800 3950);
DISPLAY 0.872340 (2800 3950);
PAINT GREEN (2800 3950);
DISPLAY INVISIBLE (2800 3950);
FORCEPROP 1 LAST HDL_TAP TRUE
J 0
(3125 3775);
DISPLAY 0.872340 (3125 3775);
DISPLAY INVISIBLE (3125 3775);
FORCEPROP 1 LAST PATH I86
J 0
(2798 3900);
DISPLAY 0.872340 (2798 3900);
PAINT GREEN (2798 3900);
DISPLAY INVISIBLE (2798 3900);
FORCEADD TAP..1
(2800 3950);
FORCEPROP 3 LASTPIN (2750 3950) SIG_NAME M_A_CPU0_SA_DQS_DP<4>
J 0
(2760 3960);
DISPLAY 0.659574 (2760 3960);
PAINT MONO (2760 3960);
DISPLAY INVISIBLE (2760 3960);
FORCEPROP 1 LASTPIN (2750 3950) BN 4
J 0
(2738 3958);
DISPLAY 0.680851 (2738 3958);
PAINT GREEN (2738 3958);
FORCEPROP 2 LAST CDS_LIB standard
J 0
(2800 3950);
DISPLAY INVISIBLE (2800 3950);
FORCEPROP 1 LAST BODY_TYPE PLUMBING
J 0
(2800 4000);
DISPLAY 0.872340 (2800 4000);
PAINT GREEN (2800 4000);
DISPLAY INVISIBLE (2800 4000);
FORCEPROP 1 LAST HDL_TAP TRUE
J 0
(3125 3825);
DISPLAY 0.872340 (3125 3825);
DISPLAY INVISIBLE (3125 3825);
FORCEPROP 1 LAST PATH I87
J 0
(2798 3950);
DISPLAY 0.872340 (2798 3950);
PAINT GREEN (2798 3950);
DISPLAY INVISIBLE (2798 3950);
FORCEADD TAP..1
(2800 4050);
FORCEPROP 3 LASTPIN (2750 4050) SIG_NAME M_A_CPU0_SA_DQS_DP<6>
J 0
(2760 4060);
DISPLAY 0.659574 (2760 4060);
PAINT MONO (2760 4060);
DISPLAY INVISIBLE (2760 4060);
FORCEPROP 1 LASTPIN (2750 4050) BN 6
J 0
(2738 4058);
DISPLAY 0.680851 (2738 4058);
PAINT GREEN (2738 4058);
FORCEPROP 2 LAST CDS_LIB standard
J 0
(2800 4050);
DISPLAY INVISIBLE (2800 4050);
FORCEPROP 1 LAST BODY_TYPE PLUMBING
J 0
(2800 4100);
DISPLAY 0.872340 (2800 4100);
PAINT GREEN (2800 4100);
DISPLAY INVISIBLE (2800 4100);
FORCEPROP 1 LAST HDL_TAP TRUE
J 0
(3125 3925);
DISPLAY 0.872340 (3125 3925);
DISPLAY INVISIBLE (3125 3925);
FORCEPROP 1 LAST PATH I88
J 0
(2798 4050);
DISPLAY 0.872340 (2798 4050);
PAINT GREEN (2798 4050);
DISPLAY INVISIBLE (2798 4050);
FORCEADD TAP..1
(2800 4000);
FORCEPROP 3 LASTPIN (2750 4000) SIG_NAME M_A_CPU0_SA_DQS_DP<5>
J 0
(2760 4010);
DISPLAY 0.659574 (2760 4010);
PAINT MONO (2760 4010);
DISPLAY INVISIBLE (2760 4010);
FORCEPROP 1 LASTPIN (2750 4000) BN 5
J 0
(2738 4008);
DISPLAY 0.680851 (2738 4008);
PAINT GREEN (2738 4008);
FORCEPROP 2 LAST CDS_LIB standard
J 0
(2800 4000);
DISPLAY INVISIBLE (2800 4000);
FORCEPROP 1 LAST BODY_TYPE PLUMBING
J 0
(2800 4050);
DISPLAY 0.872340 (2800 4050);
PAINT GREEN (2800 4050);
DISPLAY INVISIBLE (2800 4050);
FORCEPROP 1 LAST HDL_TAP TRUE
J 0
(3125 3875);
DISPLAY 0.872340 (3125 3875);
DISPLAY INVISIBLE (3125 3875);
FORCEPROP 1 LAST PATH I89
J 0
(2798 4000);
DISPLAY 0.872340 (2798 4000);
PAINT GREEN (2798 4000);
DISPLAY INVISIBLE (2798 4000);
FORCEADD TAP..1
R 2
(-625 3450);
FORCEPROP 3 LASTPIN (-575 3450) SIG_NAME M_A_CPU0_SA_DQ<16>
J 0
(-565 3460);
DISPLAY 0.659574 (-565 3460);
PAINT MONO (-565 3460);
DISPLAY INVISIBLE (-565 3460);
FORCEPROP 1 LASTPIN (-575 3450) BN 16
J 2
(-563 3458);
DISPLAY 0.680851 (-563 3458);
PAINT GREEN (-563 3458);
FORCEPROP 2 LAST CDS_LIB standard
J 0
(-625 3450);
DISPLAY INVISIBLE (-625 3450);
FORCEPROP 1 LAST BODY_TYPE PLUMBING
J 2
(-625 3500);
DISPLAY 0.872340 (-625 3500);
PAINT GREEN (-625 3500);
DISPLAY INVISIBLE (-625 3500);
FORCEPROP 1 LAST HDL_TAP TRUE
J 2
(-950 3325);
DISPLAY 0.872340 (-950 3325);
DISPLAY INVISIBLE (-950 3325);
FORCEPROP 1 LAST PATH I9
J 2
(-623 3450);
DISPLAY 0.872340 (-623 3450);
PAINT GREEN (-623 3450);
DISPLAY INVISIBLE (-623 3450);
FORCEADD TAP..1
(2800 4100);
FORCEPROP 3 LASTPIN (2750 4100) SIG_NAME M_A_CPU0_SA_DQS_DP<7>
J 0
(2760 4110);
DISPLAY 0.659574 (2760 4110);
PAINT MONO (2760 4110);
DISPLAY INVISIBLE (2760 4110);
FORCEPROP 1 LASTPIN (2750 4100) BN 7
J 0
(2738 4108);
DISPLAY 0.680851 (2738 4108);
PAINT GREEN (2738 4108);
FORCEPROP 2 LAST CDS_LIB standard
J 0
(2800 4100);
DISPLAY INVISIBLE (2800 4100);
FORCEPROP 1 LAST BODY_TYPE PLUMBING
J 0
(2800 4150);
DISPLAY 0.872340 (2800 4150);
PAINT GREEN (2800 4150);
DISPLAY INVISIBLE (2800 4150);
FORCEPROP 1 LAST HDL_TAP TRUE
J 0
(3125 3975);
DISPLAY 0.872340 (3125 3975);
DISPLAY INVISIBLE (3125 3975);
FORCEPROP 1 LAST PATH I90
J 0
(2798 4100);
DISPLAY 0.872340 (2798 4100);
PAINT GREEN (2798 4100);
DISPLAY INVISIBLE (2798 4100);
FORCEADD TAP..1
(2800 4150);
FORCEPROP 3 LASTPIN (2750 4150) SIG_NAME M_A_CPU0_SA_DQS_DP<8>
J 0
(2760 4160);
DISPLAY 0.659574 (2760 4160);
PAINT MONO (2760 4160);
DISPLAY INVISIBLE (2760 4160);
FORCEPROP 1 LASTPIN (2750 4150) BN 8
J 0
(2738 4158);
DISPLAY 0.680851 (2738 4158);
PAINT GREEN (2738 4158);
FORCEPROP 2 LAST CDS_LIB standard
J 0
(2800 4150);
DISPLAY INVISIBLE (2800 4150);
FORCEPROP 1 LAST BODY_TYPE PLUMBING
J 0
(2800 4200);
DISPLAY 0.872340 (2800 4200);
PAINT GREEN (2800 4200);
DISPLAY INVISIBLE (2800 4200);
FORCEPROP 1 LAST HDL_TAP TRUE
J 0
(3125 4025);
DISPLAY 0.872340 (3125 4025);
DISPLAY INVISIBLE (3125 4025);
FORCEPROP 1 LAST PATH I91
J 0
(2798 4150);
DISPLAY 0.872340 (2798 4150);
PAINT GREEN (2798 4150);
DISPLAY INVISIBLE (2798 4150);
FORCEADD TAP..1
(2800 4200);
FORCEPROP 3 LASTPIN (2750 4200) SIG_NAME M_A_CPU0_SA_DQS_DP<9>
J 0
(2760 4210);
DISPLAY 0.659574 (2760 4210);
PAINT MONO (2760 4210);
DISPLAY INVISIBLE (2760 4210);
FORCEPROP 1 LASTPIN (2750 4200) BN 9
J 0
(2738 4208);
DISPLAY 0.680851 (2738 4208);
PAINT GREEN (2738 4208);
FORCEPROP 2 LAST CDS_LIB standard
J 0
(2800 4200);
DISPLAY INVISIBLE (2800 4200);
FORCEPROP 1 LAST BODY_TYPE PLUMBING
J 0
(2800 4250);
DISPLAY 0.872340 (2800 4250);
PAINT GREEN (2800 4250);
DISPLAY INVISIBLE (2800 4250);
FORCEPROP 1 LAST HDL_TAP TRUE
J 0
(3125 4075);
DISPLAY 0.872340 (3125 4075);
DISPLAY INVISIBLE (3125 4075);
FORCEPROP 1 LAST PATH I92
J 0
(2798 4200);
DISPLAY 0.872340 (2798 4200);
PAINT GREEN (2798 4200);
DISPLAY INVISIBLE (2798 4200);
FORCEADD OFFPAGE..3
(3900 4225);
FORCEPROP 2 LAST $XR1 83 
J 0
(4204 4225);
DISPLAY 0.638298 (4204 4225);
PAINT MONO (4204 4225);
FORCEPROP 2 LAST $XR0 82 
J 0
(4114 4225);
DISPLAY 0.638298 (4114 4225);
PAINT MONO (4114 4225);
FORCEPROP 2 LAST CDS_LIB standard
J 2
(3900 4225);
DISPLAY INVISIBLE (3900 4225);
FORCEPROP 1 LAST OFFPAGE TRUE
J 0
(4225 4100);
DISPLAY 0.872340 (4225 4100);
DISPLAY INVISIBLE (4225 4100);
FORCEPROP 1 LAST COMMENT_BODY TRUE
J 0
(3850 4125);
DISPLAY 0.872340 (3850 4125);
PAINT GREEN (3850 4125);
DISPLAY INVISIBLE (3850 4125);
FORCEPROP 2 LAST PATH I93
J 0
(4125 4275);
DISPLAY 1.021277 (4125 4275);
DISPLAY INVISIBLE (4125 4275);
FORCEADD TAP..1
(2800 3200);
FORCEPROP 3 LASTPIN (2750 3200) SIG_NAME M_A_CPU0_SA_DQS_DN<0>
J 0
(2760 3210);
DISPLAY 0.659574 (2760 3210);
PAINT MONO (2760 3210);
DISPLAY INVISIBLE (2760 3210);
FORCEPROP 1 LASTPIN (2750 3200) BN 0
J 0
(2738 3208);
DISPLAY 0.680851 (2738 3208);
PAINT GREEN (2738 3208);
FORCEPROP 2 LAST CDS_LIB standard
J 0
(2800 3200);
DISPLAY INVISIBLE (2800 3200);
FORCEPROP 1 LAST BODY_TYPE PLUMBING
J 0
(2800 3250);
DISPLAY 0.872340 (2800 3250);
PAINT GREEN (2800 3250);
DISPLAY INVISIBLE (2800 3250);
FORCEPROP 1 LAST HDL_TAP TRUE
J 0
(3125 3075);
DISPLAY 0.872340 (3125 3075);
DISPLAY INVISIBLE (3125 3075);
FORCEPROP 1 LAST PATH I94
J 0
(2798 3200);
DISPLAY 0.872340 (2798 3200);
PAINT GREEN (2798 3200);
DISPLAY INVISIBLE (2798 3200);
FORCEADD OFFPAGE..3
(3900 3675);
FORCEPROP 2 LAST $XR1 83 
J 0
(4204 3675);
DISPLAY 0.638298 (4204 3675);
PAINT MONO (4204 3675);
FORCEPROP 2 LAST $XR0 82 
J 0
(4114 3675);
DISPLAY 0.638298 (4114 3675);
PAINT MONO (4114 3675);
FORCEPROP 2 LAST CDS_LIB standard
J 2
(3900 3675);
DISPLAY INVISIBLE (3900 3675);
FORCEPROP 1 LAST OFFPAGE TRUE
J 0
(4225 3550);
DISPLAY 0.872340 (4225 3550);
DISPLAY INVISIBLE (4225 3550);
FORCEPROP 1 LAST COMMENT_BODY TRUE
J 0
(3850 3575);
DISPLAY 0.872340 (3850 3575);
PAINT GREEN (3850 3575);
DISPLAY INVISIBLE (3850 3575);
FORCEPROP 2 LAST PATH I95
J 0
(4125 3725);
DISPLAY 1.021277 (4125 3725);
DISPLAY INVISIBLE (4125 3725);
FORCEADD TAP..1
(2800 3650);
FORCEPROP 3 LASTPIN (2750 3650) SIG_NAME M_A_CPU0_SA_DQS_DN<9>
J 0
(2760 3660);
DISPLAY 0.659574 (2760 3660);
PAINT MONO (2760 3660);
DISPLAY INVISIBLE (2760 3660);
FORCEPROP 1 LASTPIN (2750 3650) BN 9
J 0
(2738 3658);
DISPLAY 0.680851 (2738 3658);
PAINT GREEN (2738 3658);
FORCEPROP 2 LAST CDS_LIB standard
J 0
(2800 3650);
DISPLAY INVISIBLE (2800 3650);
FORCEPROP 1 LAST BODY_TYPE PLUMBING
J 0
(2800 3700);
DISPLAY 0.872340 (2800 3700);
PAINT GREEN (2800 3700);
DISPLAY INVISIBLE (2800 3700);
FORCEPROP 1 LAST HDL_TAP TRUE
J 0
(3125 3525);
DISPLAY 0.872340 (3125 3525);
DISPLAY INVISIBLE (3125 3525);
FORCEPROP 1 LAST PATH I96
J 0
(2798 3650);
DISPLAY 0.872340 (2798 3650);
PAINT GREEN (2798 3650);
DISPLAY INVISIBLE (2798 3650);
FORCEADD TAP..1
(2800 3600);
FORCEPROP 3 LASTPIN (2750 3600) SIG_NAME M_A_CPU0_SA_DQS_DN<8>
J 0
(2760 3610);
DISPLAY 0.659574 (2760 3610);
PAINT MONO (2760 3610);
DISPLAY INVISIBLE (2760 3610);
FORCEPROP 1 LASTPIN (2750 3600) BN 8
J 0
(2738 3608);
DISPLAY 0.680851 (2738 3608);
PAINT GREEN (2738 3608);
FORCEPROP 2 LAST CDS_LIB standard
J 0
(2800 3600);
DISPLAY INVISIBLE (2800 3600);
FORCEPROP 1 LAST BODY_TYPE PLUMBING
J 0
(2800 3650);
DISPLAY 0.872340 (2800 3650);
PAINT GREEN (2800 3650);
DISPLAY INVISIBLE (2800 3650);
FORCEPROP 1 LAST HDL_TAP TRUE
J 0
(3125 3475);
DISPLAY 0.872340 (3125 3475);
DISPLAY INVISIBLE (3125 3475);
FORCEPROP 1 LAST PATH I97
J 0
(2798 3600);
DISPLAY 0.872340 (2798 3600);
PAINT GREEN (2798 3600);
DISPLAY INVISIBLE (2798 3600);
FORCEADD TAP..1
(2800 3550);
FORCEPROP 3 LASTPIN (2750 3550) SIG_NAME M_A_CPU0_SA_DQS_DN<7>
J 0
(2760 3560);
DISPLAY 0.659574 (2760 3560);
PAINT MONO (2760 3560);
DISPLAY INVISIBLE (2760 3560);
FORCEPROP 1 LASTPIN (2750 3550) BN 7
J 0
(2738 3558);
DISPLAY 0.680851 (2738 3558);
PAINT GREEN (2738 3558);
FORCEPROP 2 LAST CDS_LIB standard
J 0
(2800 3550);
DISPLAY INVISIBLE (2800 3550);
FORCEPROP 1 LAST BODY_TYPE PLUMBING
J 0
(2800 3600);
DISPLAY 0.872340 (2800 3600);
PAINT GREEN (2800 3600);
DISPLAY INVISIBLE (2800 3600);
FORCEPROP 1 LAST HDL_TAP TRUE
J 0
(3125 3425);
DISPLAY 0.872340 (3125 3425);
DISPLAY INVISIBLE (3125 3425);
FORCEPROP 1 LAST PATH I98
J 0
(2798 3550);
DISPLAY 0.872340 (2798 3550);
PAINT GREEN (2798 3550);
DISPLAY INVISIBLE (2798 3550);
FORCEADD TAP..1
(2800 3450);
FORCEPROP 3 LASTPIN (2750 3450) SIG_NAME M_A_CPU0_SA_DQS_DN<5>
J 0
(2760 3460);
DISPLAY 0.659574 (2760 3460);
PAINT MONO (2760 3460);
DISPLAY INVISIBLE (2760 3460);
FORCEPROP 1 LASTPIN (2750 3450) BN 5
J 0
(2738 3458);
DISPLAY 0.680851 (2738 3458);
PAINT GREEN (2738 3458);
FORCEPROP 2 LAST CDS_LIB standard
J 0
(2800 3450);
DISPLAY INVISIBLE (2800 3450);
FORCEPROP 1 LAST BODY_TYPE PLUMBING
J 0
(2800 3500);
DISPLAY 0.872340 (2800 3500);
PAINT GREEN (2800 3500);
DISPLAY INVISIBLE (2800 3500);
FORCEPROP 1 LAST HDL_TAP TRUE
J 0
(3125 3325);
DISPLAY 0.872340 (3125 3325);
DISPLAY INVISIBLE (3125 3325);
FORCEPROP 1 LAST PATH I99
J 0
(2798 3450);
DISPLAY 0.872340 (2798 3450);
PAINT GREEN (2798 3450);
DISPLAY INVISIBLE (2798 3450);
FORCEADD QUANTA_TITLE_BLOCK_C..1
(5725 -1300);
FORCEPROP 0 LAST CDS_CON_LAST_MODIFIED Fri Aug 25 14:00:06 2023
J 0
(3840 -1285);
PAINT MONO (3840 -1285);
DISPLAY INVISIBLE (3840 -1285);
FORCEPROP 2 LAST CUSTOM_TXT_CDS <XR_PAGE_TITLE>
J 0
(-2165 3950);
DISPLAY 0.638298 (-2165 3950);
PAINT PINK (-2165 3950);
DISPLAY INVISIBLE (-2165 3950);
FORCEPROP 2 LAST CUSTOM_TXT_CDS <Q_PROJ>
J 0
(3343 -1198);
DISPLAY 1.212766 (3343 -1198);
FORCEPROP 2 LAST CUSTOM_TXT_CDS <CON_LAST_MODIFIED>
J 0
(3825 -1275);
DISPLAY 0.978723 (3825 -1275);
FORCEPROP 2 LAST CUSTOM_TXT_CDS <CON_PAGE_NUM> OF <CON_TOTAL_PAGES>
J 0
(5279 -1282);
DISPLAY 0.978723 (5279 -1282);
FORCEPROP 2 LAST CUSTOM_TXT_CDS <Q_NUMBER>
J 0
(4322 -1197);
DISPLAY 1.212766 (4322 -1197);
FORCEPROP 2 LAST CUSTOM_TXT_CDS <Q_REV>
J 0
(5541 -1197);
DISPLAY 1.212766 (5541 -1197);
FORCEPROP 1 LAST CUSTOM_TXT_CDS <NAME_2>
J 0
(2550 -1250);
FORCEPROP 1 LAST CUSTOM_TXT_CDS <NAME_1>
J 0
(2550 -1125);
FORCEPROP 1 LAST Q_TITLE SPR CPU0 - DDR CH A (8 OF 30)
J 0
(-3641 -1274);
DISPLAY 1.957447 (-3641 -1274);
PAINT GREEN (-3641 -1274);
FORCEPROP 1 LAST Q_DEPT 
J 1
(1962 -1251);
DISPLAY 1.957447 (1962 -1251);
PAINT GREEN (1962 -1251);
FORCEPROP 2 LAST PAGE_BORDER TRUE
J 0
(-2165 3950);
DISPLAY 0.638298 (-2165 3950);
PAINT PINK (-2165 3950);
DISPLAY INVISIBLE (-2165 3950);
FORCEPROP 1 LAST CDS_LMAN_SYM_OUTLINE -9475,6775,100,-125
J 0
(5725 -1300);
DISPLAY 0.468085 (5725 -1300);
PAINT GREEN (5725 -1300);
DISPLAY INVISIBLE (5725 -1300);
FORCEPROP 2 LAST CDS_LIB pure_quanta
J 0
(5725 -1300);
PAINT MONO (5725 -1300);
DISPLAY INVISIBLE (5725 -1300);
FORCEPROP 2 LAST CDS_XR_PAGE_TITLE CR-20 : @S9S_MB_2U_LIB.S9S_MB_2U(SCH_1):PAGE20
J 0
(-2165 3950);
DISPLAY 0.638298 (-2165 3950);
PAINT PINK (-2165 3950);
DISPLAY INVISIBLE (-2165 3950);
FORCEPROP 1 LAST COMMENT_BODY TRUE
J 0
(5737 -1313);
DISPLAY 0.978723 (5737 -1313);
PAINT GREEN (5737 -1313);
DISPLAY INVISIBLE (5737 -1313);
WIRE 17 -1 (2850 1875)(2850 1925);
WIRE 17 -1 (2850 1825)(2850 1875);
WIRE 17 -1 (2850 1925)(3850 1925);
FORCEPROP 2 LAST SIG_NAME M_A_CPU0_SA_CA<6:0>
J 0
(2990 1935);
DISPLAY 0.680851 (2990 1935);
PAINT WHITE (2990 1935);
WIRE 17 -1 (2850 1775)(2850 1825);
WIRE 17 -1 (2850 1725)(2850 1775);
WIRE 17 -1 (2850 1675)(2850 1725);
WIRE 17 -1 (2850 1625)(2850 1675);
WIRE 17 -1 (2850 875)(2850 925);
WIRE 17 -1 (2850 825)(2850 875);
WIRE 17 -1 (2850 925)(3850 925);
FORCEPROP 2 LAST SIG_NAME M_A_CPU0_SA_CS_N<3:0>
J 0
(2990 935);
DISPLAY 0.680851 (2990 935);
PAINT WHITE (2990 935);
WIRE 17 -1 (2850 775)(2850 825);
WIRE 17 -1 (2850 3625)(2850 3675);
WIRE 17 -1 (2850 3575)(2850 3625);
WIRE 17 -1 (2850 3675)(3850 3675);
FORCEPROP 2 LAST SIG_NAME M_A_CPU0_SA_DQS_DN<9:0>
J 0
(2990 3685);
DISPLAY 0.680851 (2990 3685);
PAINT WHITE (2990 3685);
WIRE 17 -1 (2850 3525)(2850 3575);
WIRE 17 -1 (2850 3475)(2850 3525);
WIRE 17 -1 (2850 3425)(2850 3475);
WIRE 17 -1 (2850 3375)(2850 3425);
WIRE 17 -1 (2850 3325)(2850 3375);
WIRE 17 -1 (2850 3275)(2850 3325);
WIRE 17 -1 (2850 3225)(2850 3275);
WIRE 17 -1 (2850 4175)(2850 4225);
WIRE 17 -1 (2850 4125)(2850 4175);
WIRE 17 -1 (2850 4225)(3850 4225);
FORCEPROP 2 LAST SIG_NAME M_A_CPU0_SA_DQS_DP<9:0>
J 0
(2990 4235);
DISPLAY 0.680851 (2990 4235);
PAINT WHITE (2990 4235);
WIRE 17 -1 (2850 4075)(2850 4125);
WIRE 17 -1 (2850 4025)(2850 4075);
WIRE 17 -1 (2850 3975)(2850 4025);
WIRE 17 -1 (2850 3925)(2850 3975);
WIRE 17 -1 (2850 3875)(2850 3925);
WIRE 17 -1 (2850 3825)(2850 3875);
WIRE 17 -1 (2850 3775)(2850 3825);
WIRE 17 -1 (2850 1325)(2850 1375);
WIRE 17 -1 (2850 1275)(2850 1325);
WIRE 17 -1 (2850 1375)(2850 1425);
WIRE 17 -1 (2850 1425)(3850 1425);
FORCEPROP 2 LAST SIG_NAME M_A_CPU0_SB_CA<6:0>
J 0
(2990 1435);
DISPLAY 0.680851 (2990 1435);
PAINT WHITE (2990 1435);
WIRE 17 -1 (2850 1225)(2850 1275);
WIRE 17 -1 (2850 1175)(2850 1225);
WIRE 17 -1 (2850 1125)(2850 1175);
WIRE 17 -1 (2850 575)(2850 625);
WIRE 17 -1 (2850 525)(2850 575);
WIRE 17 -1 (2850 625)(3850 625);
FORCEPROP 2 LAST SIG_NAME M_A_CPU0_SB_CS_N<3:0>
J 0
(2990 635);
DISPLAY 0.680851 (2990 635);
PAINT WHITE (2990 635);
WIRE 17 -1 (2850 475)(2850 525);
WIRE 17 -1 (2850 2475)(2850 2525);
WIRE 17 -1 (2850 2425)(2850 2475);
WIRE 17 -1 (2850 2525)(3850 2525);
FORCEPROP 2 LAST SIG_NAME M_A_CPU0_SB_DQS_DN<9:0>
J 0
(2990 2535);
DISPLAY 0.680851 (2990 2535);
PAINT WHITE (2990 2535);
WIRE 17 -1 (2850 2375)(2850 2425);
WIRE 17 -1 (2850 2325)(2850 2375);
WIRE 17 -1 (2850 2275)(2850 2325);
WIRE 17 -1 (2850 2225)(2850 2275);
WIRE 17 -1 (2850 2175)(2850 2225);
WIRE 17 -1 (2850 2125)(2850 2175);
WIRE 17 -1 (2850 2075)(2850 2125);
WIRE 17 -1 (2850 3025)(2850 3075);
WIRE 17 -1 (2850 2975)(2850 3025);
WIRE 17 -1 (2850 3075)(3850 3075);
FORCEPROP 2 LAST SIG_NAME M_A_CPU0_SB_DQS_DP<9:0>
J 0
(2990 3085);
DISPLAY 0.680851 (2990 3085);
PAINT WHITE (2990 3085);
WIRE 17 -1 (2850 2925)(2850 2975);
WIRE 17 -1 (2850 2875)(2850 2925);
WIRE 17 -1 (2850 2825)(2850 2875);
WIRE 17 -1 (2850 2775)(2850 2825);
WIRE 17 -1 (2850 2725)(2850 2775);
WIRE 17 -1 (2850 2675)(2850 2725);
WIRE 17 -1 (2850 2625)(2850 2675);
WIRE 17 -1 (-675 275)(-675 325);
WIRE 17 -1 (-675 325)(-675 375);
WIRE 17 -1 (-675 375)(-675 425);
WIRE 17 -1 (-675 425)(-675 475);
WIRE 17 -1 (-675 475)(-675 525);
WIRE 17 -1 (-675 525)(-675 575);
WIRE 17 -1 (-675 575)(-675 625);
WIRE 17 -1 (-1600 625)(-675 625);
FORCEPROP 2 LAST SIG_NAME M_A_CPU0_SB_CB<7:0>
J 0
(-1460 635);
DISPLAY 0.680851 (-1460 635);
PAINT WHITE (-1460 635);
WIRE 17 -1 (-675 675)(-675 725);
WIRE 17 -1 (-675 725)(-675 775);
WIRE 17 -1 (-675 775)(-675 825);
WIRE 17 -1 (-675 825)(-675 875);
WIRE 17 -1 (-675 875)(-675 925);
WIRE 17 -1 (-675 925)(-675 975);
WIRE 17 -1 (-675 975)(-675 1025);
WIRE 17 -1 (-675 1025)(-675 1075);
WIRE 17 -1 (-675 1075)(-675 1125);
WIRE 17 -1 (-675 1125)(-675 1175);
WIRE 17 -1 (-675 1175)(-675 1225);
WIRE 17 -1 (-675 1225)(-675 1275);
WIRE 17 -1 (-675 1275)(-675 1325);
WIRE 17 -1 (-675 1325)(-675 1375);
WIRE 17 -1 (-675 1375)(-675 1425);
WIRE 17 -1 (-675 1425)(-675 1475);
WIRE 17 -1 (-675 1475)(-675 1525);
WIRE 17 -1 (-675 1525)(-675 1575);
WIRE 17 -1 (-675 1575)(-675 1625);
WIRE 17 -1 (-675 1625)(-675 1675);
WIRE 17 -1 (-675 1675)(-675 1725);
WIRE 17 -1 (-675 1725)(-675 1775);
WIRE 17 -1 (-675 1775)(-675 1825);
WIRE 17 -1 (-675 1825)(-675 1875);
WIRE 17 -1 (-675 1875)(-675 1925);
WIRE 17 -1 (-675 1925)(-675 1975);
WIRE 17 -1 (-675 1975)(-675 2025);
WIRE 17 -1 (-675 2025)(-675 2075);
WIRE 17 -1 (-675 2075)(-675 2125);
WIRE 17 -1 (-675 2125)(-675 2175);
WIRE 17 -1 (-675 2175)(-675 2225);
WIRE 17 -1 (-1600 2225)(-675 2225);
FORCEPROP 2 LAST SIG_NAME M_A_CPU0_SB_DQ<31:0>
J 0
(-1460 2235);
DISPLAY 0.680851 (-1460 2235);
PAINT WHITE (-1460 2235);
WIRE 17 -1 (-675 2275)(-675 2325);
WIRE 17 -1 (-675 2325)(-675 2375);
WIRE 17 -1 (-675 2375)(-675 2425);
WIRE 17 -1 (-675 2425)(-675 2475);
WIRE 17 -1 (-675 2475)(-675 2525);
WIRE 17 -1 (-675 2525)(-675 2575);
WIRE 17 -1 (-675 2575)(-675 2625);
WIRE 17 -1 (-1600 2625)(-675 2625);
FORCEPROP 2 LAST SIG_NAME M_A_CPU0_SA_CB<7:0>
J 0
(-1460 2635);
DISPLAY 0.680851 (-1460 2635);
PAINT WHITE (-1460 2635);
WIRE 17 -1 (-675 2725)(-675 2775);
WIRE 17 -1 (-675 2675)(-675 2725);
WIRE 17 -1 (-675 2775)(-675 2825);
WIRE 17 -1 (-675 2825)(-675 2875);
WIRE 17 -1 (-675 2875)(-675 2925);
WIRE 17 -1 (-675 2925)(-675 2975);
WIRE 17 -1 (-675 2975)(-675 3025);
WIRE 17 -1 (-675 3025)(-675 3075);
WIRE 17 -1 (-675 3075)(-675 3125);
WIRE 17 -1 (-675 3125)(-675 3175);
WIRE 17 -1 (-675 3175)(-675 3225);
WIRE 17 -1 (-675 3225)(-675 3275);
WIRE 17 -1 (-675 3275)(-675 3325);
WIRE 17 -1 (-675 3325)(-675 3375);
WIRE 17 -1 (-675 3375)(-675 3425);
WIRE 17 -1 (-675 3425)(-675 3475);
WIRE 17 -1 (-675 3475)(-675 3525);
WIRE 17 -1 (-675 3525)(-675 3575);
WIRE 17 -1 (-675 3575)(-675 3625);
WIRE 17 -1 (-675 3625)(-675 3675);
WIRE 17 -1 (-675 3675)(-675 3725);
WIRE 17 -1 (-675 3725)(-675 3775);
WIRE 17 -1 (-675 3775)(-675 3825);
WIRE 17 -1 (-675 3825)(-675 3875);
WIRE 17 -1 (-675 3875)(-675 3925);
WIRE 17 -1 (-675 3925)(-675 3975);
WIRE 17 -1 (-675 3975)(-675 4025);
WIRE 17 -1 (-675 4025)(-675 4075);
WIRE 17 -1 (-675 4075)(-675 4125);
WIRE 17 -1 (-675 4125)(-675 4175);
WIRE 17 -1 (-675 4175)(-675 4225);
WIRE 17 -1 (-1600 4225)(-675 4225);
FORCEPROP 2 LAST SIG_NAME M_A_CPU0_SA_DQ<31:0>
J 0
(-1460 4235);
DISPLAY 0.680851 (-1460 4235);
PAINT WHITE (-1460 4235);
WIRE 17 -1 (-675 125)(-675 175);
WIRE 17 -1 (-1600 175)(-675 175);
FORCEPROP 2 LAST SIG_NAME M_A_CPU0_CLK_DP<1:0>
J 0
(-1460 185);
DISPLAY 0.680851 (-1460 185);
PAINT WHITE (-1460 185);
WIRE 17 -1 (-675 25)(-675 75);
WIRE 17 -1 (-1600 75)(-675 75);
FORCEPROP 2 LAST SIG_NAME M_A_CPU0_CLK_DN<1:0>
J 0
(-1460 85);
DISPLAY 0.680851 (-1460 85);
PAINT WHITE (-1460 85);
WIRE 16 -1 (-575 3450)(-125 3450);
WIRE 16 -1 (-575 3400)(-125 3400);
WIRE 16 -1 (-575 3350)(-125 3350);
WIRE 16 -1 (-575 3300)(-125 3300);
WIRE 16 -1 (-575 3250)(-125 3250);
WIRE 16 -1 (-575 3200)(-125 3200);
WIRE 16 -1 (-575 3150)(-125 3150);
WIRE 16 -1 (-575 3050)(-125 3050);
WIRE 16 -1 (-575 3000)(-125 3000);
WIRE 16 -1 (-575 2900)(-125 2900);
WIRE 16 -1 (-575 2750)(-125 2750);
WIRE 16 -1 (-575 2650)(-125 2650);
WIRE 16 -1 (-575 2400)(-125 2400);
WIRE 16 -1 (2325 1400)(2750 1400);
WIRE 16 -1 (-575 50)(-125 50);
WIRE 16 -1 (-575 0)(-125 0);
WIRE 16 -1 (-575 150)(-125 150);
WIRE 16 -1 (-575 100)(-125 100);
WIRE 16 -1 (-575 4200)(-125 4200);
WIRE 16 -1 (-575 4150)(-125 4150);
WIRE 16 -1 (-575 4100)(-125 4100);
WIRE 16 -1 (-575 4050)(-125 4050);
WIRE 16 -1 (-575 4000)(-125 4000);
WIRE 16 -1 (-575 3950)(-125 3950);
WIRE 16 -1 (-575 3900)(-125 3900);
WIRE 16 -1 (-575 3850)(-125 3850);
WIRE 16 -1 (-575 3800)(-125 3800);
WIRE 16 -1 (-575 3750)(-125 3750);
WIRE 16 -1 (-575 3700)(-125 3700);
WIRE 16 -1 (-575 3650)(-125 3650);
WIRE 16 -1 (-575 3600)(-125 3600);
WIRE 16 -1 (-575 3550)(-125 3550);
WIRE 16 -1 (-575 3500)(-125 3500);
WIRE 16 -1 (-575 3100)(-125 3100);
WIRE 16 -1 (-575 2950)(-125 2950);
WIRE 16 -1 (-575 2850)(-125 2850);
WIRE 16 -1 (-575 2800)(-125 2800);
WIRE 16 -1 (-575 2700)(-125 2700);
WIRE 16 -1 (-575 2600)(-125 2600);
WIRE 16 -1 (-575 2550)(-125 2550);
WIRE 16 -1 (-575 2500)(-125 2500);
WIRE 16 -1 (-575 2450)(-125 2450);
WIRE 16 -1 (-575 2350)(-125 2350);
WIRE 16 -1 (-575 2300)(-125 2300);
WIRE 16 -1 (-575 2250)(-125 2250);
WIRE 16 -1 (-575 2200)(-125 2200);
WIRE 16 -1 (-575 2150)(-125 2150);
WIRE 16 -1 (-575 2100)(-125 2100);
WIRE 16 -1 (-575 2050)(-125 2050);
WIRE 16 -1 (-575 2000)(-125 2000);
WIRE 16 -1 (-575 1950)(-125 1950);
WIRE 16 -1 (-575 1900)(-125 1900);
WIRE 16 -1 (-575 1850)(-125 1850);
WIRE 16 -1 (-575 1800)(-125 1800);
WIRE 16 -1 (-575 1750)(-125 1750);
WIRE 16 -1 (-575 1700)(-125 1700);
WIRE 16 -1 (-575 1650)(-125 1650);
WIRE 16 -1 (-575 1600)(-125 1600);
WIRE 16 -1 (-575 1550)(-125 1550);
WIRE 16 -1 (-575 1500)(-125 1500);
WIRE 16 -1 (-575 1450)(-125 1450);
WIRE 16 -1 (-575 1400)(-125 1400);
WIRE 16 -1 (-575 1350)(-125 1350);
WIRE 16 -1 (-575 1300)(-125 1300);
WIRE 16 -1 (-575 1250)(-125 1250);
WIRE 16 -1 (-575 1200)(-125 1200);
WIRE 16 -1 (-575 1150)(-125 1150);
WIRE 16 -1 (-575 1100)(-125 1100);
WIRE 16 -1 (-575 1050)(-125 1050);
WIRE 16 -1 (-575 1000)(-125 1000);
WIRE 16 -1 (-575 950)(-125 950);
WIRE 16 -1 (-575 900)(-125 900);
WIRE 16 -1 (-575 850)(-125 850);
WIRE 16 -1 (-575 800)(-125 800);
WIRE 16 -1 (-575 750)(-125 750);
WIRE 16 -1 (-575 700)(-125 700);
WIRE 16 -1 (-575 650)(-125 650);
WIRE 16 -1 (-575 600)(-125 600);
WIRE 16 -1 (-575 550)(-125 550);
WIRE 16 -1 (-575 500)(-125 500);
WIRE 16 -1 (-575 450)(-125 450);
WIRE 16 -1 (-575 400)(-125 400);
WIRE 16 -1 (-575 350)(-125 350);
WIRE 16 -1 (-575 300)(-125 300);
WIRE 16 -1 (-575 250)(-125 250);
WIRE 16 -1 (3850 1050)(2325 1050);
FORCEPROP 2 LAST SIG_NAME M_A_CPU0_SB_PAR
J 0
(2959 1059);
DISPLAY 0.680851 (2959 1059);
PAINT WHITE (2959 1059);
WIRE 16 -1 (2325 2600)(2750 2600);
WIRE 16 -1 (2325 2650)(2750 2650);
WIRE 16 -1 (2325 2700)(2750 2700);
WIRE 16 -1 (2325 2750)(2750 2750);
WIRE 16 -1 (2325 2800)(2750 2800);
WIRE 16 -1 (2325 2850)(2750 2850);
WIRE 16 -1 (2325 2900)(2750 2900);
WIRE 16 -1 (2325 2950)(2750 2950);
WIRE 16 -1 (2325 3000)(2750 3000);
WIRE 16 -1 (2325 3050)(2750 3050);
WIRE 16 -1 (2325 2050)(2750 2050);
WIRE 16 -1 (2325 2100)(2750 2100);
WIRE 16 -1 (2325 2150)(2750 2150);
WIRE 16 -1 (2325 2200)(2750 2200);
WIRE 16 -1 (2325 2250)(2750 2250);
WIRE 16 -1 (2325 2300)(2750 2300);
WIRE 16 -1 (2325 2350)(2750 2350);
WIRE 16 -1 (2325 2400)(2750 2400);
WIRE 16 -1 (2325 2450)(2750 2450);
WIRE 16 -1 (2325 2500)(2750 2500);
WIRE 16 -1 (2325 450)(2750 450);
WIRE 16 -1 (2325 500)(2750 500);
WIRE 16 -1 (2325 550)(2750 550);
WIRE 16 -1 (2325 600)(2750 600);
WIRE 16 -1 (2325 1100)(2750 1100);
WIRE 16 -1 (2325 1150)(2750 1150);
WIRE 16 -1 (2325 1200)(2750 1200);
WIRE 16 -1 (2325 1250)(2750 1250);
WIRE 16 -1 (2325 1300)(2750 1300);
WIRE 16 -1 (2325 1350)(2750 1350);
WIRE 16 -1 (3850 1550)(2325 1550);
FORCEPROP 2 LAST SIG_NAME M_A_CPU0_SA_PAR
J 0
(2959 1559);
DISPLAY 0.680851 (2959 1559);
PAINT WHITE (2959 1559);
WIRE 16 -1 (2325 3750)(2750 3750);
WIRE 16 -1 (2325 3800)(2750 3800);
WIRE 16 -1 (2325 3850)(2750 3850);
WIRE 16 -1 (2325 3900)(2750 3900);
WIRE 16 -1 (2325 3950)(2750 3950);
WIRE 16 -1 (2325 4000)(2750 4000);
WIRE 16 -1 (2325 4050)(2750 4050);
WIRE 16 -1 (2325 4100)(2750 4100);
WIRE 16 -1 (2325 4150)(2750 4150);
WIRE 16 -1 (2325 4200)(2750 4200);
WIRE 16 -1 (2325 3200)(2750 3200);
WIRE 16 -1 (2325 3250)(2750 3250);
WIRE 16 -1 (2325 3300)(2750 3300);
WIRE 16 -1 (2325 3350)(2750 3350);
WIRE 16 -1 (2325 3400)(2750 3400);
WIRE 16 -1 (2325 3450)(2750 3450);
WIRE 16 -1 (2325 3500)(2750 3500);
WIRE 16 -1 (2325 3550)(2750 3550);
WIRE 16 -1 (2325 3600)(2750 3600);
WIRE 16 -1 (2325 3650)(2750 3650);
WIRE 16 -1 (2325 750)(2750 750);
WIRE 16 -1 (2325 800)(2750 800);
WIRE 16 -1 (2325 850)(2750 850);
WIRE 16 -1 (2325 900)(2750 900);
WIRE 16 -1 (2325 1600)(2750 1600);
WIRE 16 -1 (2325 1650)(2750 1650);
WIRE 16 -1 (2325 1700)(2750 1700);
WIRE 16 -1 (2325 1750)(2750 1750);
WIRE 16 -1 (2325 1800)(2750 1800);
WIRE 16 -1 (2325 1850)(2750 1850);
WIRE 16 -1 (2325 1900)(2750 1900);
WIRE 16 -1 (3850 100)(2325 100);
FORCEPROP 2 LAST SIG_NAME M_A_CPU0_SB_RSP<0>
J 0
(2959 109);
DISPLAY 0.680851 (2959 109);
PAINT WHITE (2959 109);
WIRE 16 -1 (3850 150)(2325 150);
FORCEPROP 2 LAST SIG_NAME M_A_CPU0_SB_RSP<1>
J 0
(2959 159);
DISPLAY 0.680851 (2959 159);
PAINT WHITE (2959 159);
WIRE 16 -1 (3850 250)(2325 250);
FORCEPROP 2 LAST SIG_NAME M_A_CPU0_SA_RSP<0>
J 0
(2959 259);
DISPLAY 0.680851 (2959 259);
PAINT WHITE (2959 259);
WIRE 16 -1 (3850 300)(2325 300);
FORCEPROP 2 LAST SIG_NAME M_A_CPU0_SA_RSP<1>
J 0
(2959 309);
DISPLAY 0.680851 (2959 309);
PAINT WHITE (2959 309);
WIRE 16 -1 (3850 0)(2325 0);
FORCEPROP 2 LAST SIG_NAME M_A_CPU0_ALERT_N
J 0
(2959 9);
DISPLAY 0.680851 (2959 9);
PAINT WHITE (2959 9);
QUIT
